FILE_TYPE = CONNECTIVITY;
{Allegro Design Entry HDL 17.4-2019 S026 (4007227) 1/17/2022}
"PAGE_NUMBER" = 80;
0"NC";
1"P3V3_AUX\g";
2"E1S_0_P3V3_EN";
3"BMC_FPGA_LED1";
4"P3V3_E1S_PWRGD_0_R";
5"RST_PERST_CPU1_SWB_1_N";
6"P3V3_E1S_0_EN_R";
7"HPDB_HSC_PWRGD_ISO_R"CDS_PHYS_NET_NAME"FM_SWB_PWR_EN";
8"FM_LED_PWRGD_PVDD11_S3_P0";
9"FM_LED_PWRGD_PVDDIO_P0";
10"FM_LED_PWRGD_PVDD18_S5_P0";
11"P12V_E1S_0_EN";
12"FM_LED_PWRGD_PVDD33_S5";
13"P0V9_RETIMER_CPU0_EN_R2";
14"BMC_FPGA_LED2";
15"FM_LED_PWRGD_PVDDCR_CPU0_P1";
16"FM_PWRGD_PVDDIO_P1";
17"FM_PWRGD_PVDD18_S5_P0";
18"PWRGD_P1V2_AUX_R";
19"FM_PLD_OCP_SFF_PWR_GOOD_R";
20"P12V_E1S_0_PWRGD";
21"FM_CPU0_PWR_GOOD";
22"PWRGD_P1V8_AUX_R";
23"FM_PVDD18_S5_P0_EN";
24"PWRGD_P3V3_AUX_R";
25"FM_PWRGD_P1V8_RETIMER_CPU1"CDS_PHYS_NET_NAME"TP_SPI_PLD_D1";
26"FM_FPGA_DEBUG_SW_SPARE";
27"FM_PWRGD_PVDD11_S3_P1";
28"FM_PVDD11_S3_P1_EN";
29"FM_PWRGD_PVDD33_S5";
30"PWRGD_PVDD18_S5_R_P1";
31"P12V_SCM_PWRGD_R";
32"BMC_MONITER"CDS_PHYS_NET_NAME"GPU_3V3IO_RSVD1_ISO_R";
33"GPU_FPGA_EROT_RECOV_R_N"CDS_PHYS_NET_NAME"GPU_3V3IO_RSVD1_ISO_R";
34"FM_UART_LS_EN";
35"PRSNT_SWB_ISO_R_N";
36"GPU_FPGA_EROT_RST_R_N"CDS_PHYS_NET_NAME"GPU_3V3IO_RSVD1_ISO_R";
37"FM_PVDDCR_CPU0_P1_R_EN";
38"PVDDCR_CPU0_P0_PMALERT";
39"PRSNT_OCP_SFF_N";
40"FM_PWRGD_PVDDIO_P0";
41"FM_PVDDIO_P0_EN";
42"RST_PERST_OCP_V3_2_N";
43"FM_P5V_EN";
44"P3V3_OCP_V3_2_EN_R";
45"P0V9_RETIMER_CPU1_EN_R2";
46"FM_AC_PWR_BTN_PLD_ISO_N"CDS_PHYS_NET_NAME"GPU_FPGA_READY_ISO_R";
47"P12V_OCP_V3_2_EN_R";
48"PRSNT_HDT_N";
49"FM_NCSI_OCP_V3_2_R_OE";
50"GPU_FPGA_READY_ISO"CDS_PHYS_NET_NAME"SWB_HSC_PWRGD_ISO";
51"RST_PERST_OCP_SFF_N";
52"GPU_FPGA_BOOT_EN"CDS_PHYS_NET_NAME"SWB_HSC_PWRGD_ISO";
53"P0V9_RETIMER_CPU1_EN";
54"PU_SPI_PLD_CS_N"CDS_PHYS_NET_NAME"TP_SPI_PLD_D0";
55"GPU_BASE_STBY_EN"CDS_PHYS_NET_NAME"SWB_HSC_PWRGD_ISO";
56"FM_SMB_2_ALERT_GPU_ISO_N"CDS_PHYS_NET_NAME"SWB_HSC_PWRGD_ISO";
57"PWRGD_PVDDCR_CPU1_P1";
58"PRSNT_SWB_ISO_N";
59"GPU_FPGA_EROT_RST_N"CDS_PHYS_NET_NAME"GPU_3V3IO_RSVD1_ISO";
60"HP_LVC3_OCP_SFF_PRSNT2_PLD_N";
61"PWRGD_PVDDIO_P0";
62"FM_GPU_PWR_EN_R"CDS_PHYS_NET_NAME"GPU_3V3IO_RSVD1_ISO";
63"PWRGD_PVDDCR_CPU0_P1";
64"UART_LS_EN";
65"GPU_NVS_PWR_BRAKE_R_N"CDS_PHYS_NET_NAME"GPU_3V3IO_RSVD1_ISO_R";
66"RST_RT_CPU0_P1_PERST_R_N";
67"GPU_NVS_PWR_BRAKE_N"CDS_PHYS_NET_NAME"GPU_3V3IO_RSVD1_ISO";
68"FM_SWB_PWR_EN_R"CDS_PHYS_NET_NAME"GPU_3V3IO_RSVD1_ISO";
69"GPU_3V3IO_RSVD4_ISO"CDS_PHYS_NET_NAME"GPU_3V3IO_RSVD1_ISO";
70"FM_SWB_PWR_EN"CDS_PHYS_NET_NAME"GPU_3V3IO_RSVD1_ISO_R";
71"FM_SWB_BIC_READY_ISO_R_N"CDS_PHYS_NET_NAME"GPU_3V3IO_RSVD1_ISO_R";
72"RST_BMC_FROM_SWB_ISO_R_N"CDS_PHYS_NET_NAME"GPU_3V3IO_RSVD1_ISO_R";
73"FM_SMB_1_ALERT_GPU_ISO_R_N"CDS_PHYS_NET_NAME"GPU_3V3IO_RSVD1_ISO_R";
74"FM_CPU1_FORCE_SELFREFRESH";
75"FM_FORCE_ALL_PWRON_R";
76"FM_FORCE_ALL_PWRON";
77"CPU1_FORCE_SELFREFRESH";
78"RST_SMB_RT_R1_N";
79"CPU1_PWR_GD_IN";
80"CPU0_FORCE_SELFREFRESH";
81"CPU0_JTAG_BUF_OE";
82"PWRGD_CPU0_PWROK";
83"CPU1_NV_SAVE_N";
84"PWRGD_CPU1_PWROK";
85"FPGA_DEBUG_LED_CTRL";
86"FM_FPGA_DEBUG_LED_CTRL";
87"CPU0_PWR_BTN_N";
88"FM_P1_PCC0_N";
89"RST_RT_CPU1_P2_PERST_R_N";
90"RST_RT_CPU1_P2_RESET_R_N";
91"RST_PERST_M2_0_R_N";
92"FM_GPU_PWRGD_ISO_R"CDS_PHYS_NET_NAME"GPU_3V3IO_RSVD1_ISO_R";
93"GPU_FPGA_READY_ISO_R"CDS_PHYS_NET_NAME"GPU_3V3IO_RSVD1_ISO_R";
94"SWB_HSC_EN"CDS_PHYS_NET_NAME"GPU_3V3IO_RSVD1_ISO";
95"GPU_WP_HW_CTRL_N"CDS_PHYS_NET_NAME"GPU_BB_RSVD_1_ISO";
96"GPU_3V3IO_RSVD0_FFU_ISO"CDS_PHYS_NET_NAME"GPU_3V3IO_RSVD1_ISO";
97"GPU_PRSNT_N_ISO"CDS_PHYS_NET_NAME"SWB_HSC_PWRGD_ISO";
98"GPU_FPGA_OVERT_ISO_N"CDS_PHYS_NET_NAME"SWB_HSC_PWRGD_ISO";
99"PRSNT_CABLE_GPU_A2_ISO_N"CDS_PHYS_NET_NAME"GPU_3V3IO_RSVD0_FFU_ISO";
100"GPU_3V3IO_RSVD1_FFU_ISO"CDS_PHYS_NET_NAME"GPU_3V3IO_RSVD1_ISO";
101"GPU_3V3IO_RSVD5_FFU_ISO"CDS_PHYS_NET_NAME"GPU_3V3IO_RSVD0_FFU_ISO";
102"GPU_BASE_HMC_READY_ISO"CDS_PHYS_NET_NAME"GPU_3V3IO_RSVD0_FFU_ISO";
103"GPU_HMC_PRSNT_ISO_R_N"CDS_PHYS_NET_NAME"GPU_3V3IO_RSVD1_ISO_R";
104"PRSNT_CABLE_GPU_A1_ISO_N"CDS_PHYS_NET_NAME"GPU_3V3IO_RSVD0_FFU_ISO";
105"SWB_HSC_PWRGD_ISO_R"CDS_PHYS_NET_NAME"GPU_3V3IO_RSVD1_ISO_R";
106"GPU_FPGA_THERM_OVERT_ISO_R_N"CDS_PHYS_NET_NAME"GPU_3V3IO_RSVD1_ISO_R";
107"GPU_BASE_HMC_READY_ISO_R"CDS_PHYS_NET_NAME"GPU_3V3IO_RSVD1_ISO_R";
108"CPU0_NMI_SYNC_FLOOD_N";
109"RST_CPU0_KBRST_R_N";
110"RST_CPU1_RESETL_N";
111"RST_RT_CPU1_P1_RESET_R_N";
112"FM_P1_PCC1_N";
113"FM_P0_PCC0_N";
114"FM_P0_PCC1_N";
115"RST_RT_CPU0_P0_PERST_R_N";
116"RST_RT_CPU0_P0_RESET_R_N";
117"RST_RT_CPU1_P3_RESET_R_N";
118"RST_RT_CPU1_P3_PERST_R_N";
119"FM_SPD_CPU0_SWITCH_CTRL_N";
120"CPU0_HDT_BYPASS_SEL";
121"CPU1_PWRGD_OUT";
122"RST_RT_CPU1_P2_PERST_R2_N";
123"RST_RT_CPU1_P2_RESET_R2_N";
124"FM_P0_PCC1_R_N";
125"FM_P0_PCC0_R_N";
126"APML_CPU1_ALERT_R_N";
127"CPU1_SPD_HOST_CTRL_N";
128"RST_RT_CPU1_P3_RESET_R2_N";
129"RST_RT_CPU0_P1_RESET_R_N";
130"CPU1_SPD_HOST_CTRL_R1_N";
131"RST_RT_CPU0_P1_RESET_R2_N";
132"RST_RT_CPU0_P0_PERST_R2_N";
133"FM_ESPI_CPU0_ALERT_R_SEL";
134"FM_SMERR_LED_N";
135"CPU0_SMERR_N";
136"ESPI_CPU0_ALERT_R_N";
137"RST_ESPI_CPU0_RSTOUT_R_N";
138"ESPI_CPU0_D0";
139"FM_CPU1_NMI_SYNC_FLOOD_N";
140"FM_BIOS_POST_CMPLT_BUF_N";
141"HDT_HDR_PWROK";
142"ESPI_CPU0_D3";
143"ESPI_CPU0_D2";
144"ESPI_CPU0_D1";
145"RST_RT_CPU0_P1_PERST_R2_N";
146"RST_RT_CPU0_P0_RESET_R2_N";
147"RST_RT_CPU1_P3_PERST_R2_N";
148"APML_CPU0_ALERT_R_N";
149"FM_CPU1_SMERR_N";
150"FM_SMERR_LED_R_N";
151"ESPI_CPU0_CS1_N";
152"ESPI_CPU0_ALERT_PLD_N";
153"RST_ESPI_CPU0_RSTOUT_N";
154"CPU0_SPD_HOST_CTRL_R1_N";
155"CPU1_NMI_SYNC_FLOOD_N";
156"P12V_ALL_PWROK_R";
157"CPU1_HDT_BYPASS_SEL";
158"CPU0_SPD_HOST_CTRL_N";
159"P12V_ALL_PWROK";
160"ROM_SD_LS_OE";
161"FM_CPU1_PWRGD_OUT";
162"FM_SPD_CPU0_SWITCH_CTRL_R_N";
163"BMC_JTAG_SEL";
164"ROM_LS_EN";
165"FM_CPU1_PWR_GD_IN";
166"FM_CPU0_FORCE_SELFREFRESH";
167"SCM_IRQ_1V8_N";
168"CPU1_JTAG_BUF_OE";
169"RST_RT_CPU0_P3_RESET_R_N";
170"SCM_USB_OC_N";
171"RST_RT_CPU0_P3_PERST_R_N";
172"RST_RT_CPU0_P2_RESET_R_N";
173"RST_SMB_RT_ROM_R1_N";
174"HDT_HDR_RESET_N";
175"CLK_ESPI_CPU0_CLK1";
176"FM_JTAG_BMC_R_OE";
177"CPU0_HDT_CONN_TESTEN";
178"BIOS_DEBUG_MODE";
179"FM_CPU0_HDT_CONN_TESTEN";
180"FM_RST_CPU0_RESETL_N";
181"FM_PWRGD_CPU0_PWROK";
182"CPU0_JTAG_BUF_R_OE";
183"RST_RT_CPU1_P1_RESET_R2_N";
184"RST_RT_CPU1_P1_PERST_R2_N";
185"FM_CPU0_NV_SAVE_N";
186"FM_CPU1_SYS_RESET_N";
187"FM_CPU0_SYS_RESET_N";
188"FM_RST_CPU1_RESETL_N";
189"RST_CPU0_KBRST_N";
190"FM_CPU1_NV_SAVE_N";
191"PVDD11_S3_P0_RESET_N";
192"PVDD11_S3_P1_RESET_N";
193"FM_CPU0_NMI_SYNC_FLOOD_N";
194"FM_PWRGD_CPU1_PWROK";
195"TP_SLOT2_CLKREQ_0_R_N";
196"FM_CPU0_PWR_BTN_N";
197"FM_P1_PCC1_R_N";
198"FM_ROM_SD_LS_OE";
199"RST_RT_CPU0_P3_RESET_R2_N";
200"BMC_JTAG_SEL_R";
201"FM_ROM_LS_EN";
202"FM_PLD_CPU0_PRSNT_HDT"CDS_PHYS_NET_NAME"FM_PLD_CPU0_PRSNT_HDT";
203"GPU_3V3IO_RSVD3_ISO_R"CDS_PHYS_NET_NAME"GPU_3V3IO_RSVD1_ISO_R";
204"GPU_3V3IO_RSVD1_ISO_R"CDS_PHYS_NET_NAME"GPU_3V3IO_RSVD1_ISO_R";
205"GPU_FPGA_RST_R_N"CDS_PHYS_NET_NAME"GPU_3V3IO_RSVD1_ISO";
206"PVDD11_S3_P1_EN";
207"RST_SMB_RT_R2_N";
208"RST_SMB_RT_ROM_R2_N";
209"TP_FM_CLK_BUFFER_EN_R";
210"RST_RT_CPU0_P3_PERST_R2_N";
211"SCM_IRQ_1V8_R_N";
212"CPU1_JTAG_BUF_R_OE";
213"FM_PLD_CPU1_PRSNT_HDT"CDS_PHYS_NET_NAME"FM_PLD_CPU1_PRSNT_HDT";
214"SCM_USB_OC_R_N";
215"FM_ESPI_CPU0_ALERT_SEL";
216"CPU1_SMERR_N";
217"PWRGD_P3V3_R2";
218"SMB_CPU_5_R1_SDA";
219"SMB_CPU_5_R1_SCL";
220"RST_RT_CPU0_P2_PERST_R_N";
221"RST_RT_CPU0_P2_PERST_R2_N";
222"FM_JTAG_BMC_OE";
223"ESPI_CPU0_CS1_R_N";
224"ESPI_CPU0_R1_D0";
225"ESPI_CPU0_R1_D1";
226"ESPI_CPU0_R1_D2";
227"ESPI_CPU0_R1_D3";
228"BIOS_DEBUG_MODE_R";
229"TP_PWRGD_P12V_FAN_DR_R";
230"PWRGD_P12V_MEM_R";
231"CLK_ESPI_CPU0_R1_CLK1";
232"FM_HDT_HDR_PWROK";
233"FM_HDT_HDR_RESET_N";
234"FM_BIOS_POST_CMPLT_BUF_R_N";
235"FM_BIOS_USB_RECOVERY";
236"RST_RT_CPU0_P2_RESET_R2_N";
237"PWRGD_PVDD11_S3_P1";
238"PVDD18_S5_P1_EN";
239"FPGA_DEBUG_SW_SPARE";
240"FM_P1_PCC0_R_N";
241"FM_CPU0_SMERR_N";
242"RST_CPU0_RESETL_N";
243"RST_CPU0_PERST0_N";
244"FM_CPU0_SLP_S5_N";
245"FM_CPU0_SLP_S3_N";
246"RST_CPU0_PERST0_R_N";
247"RST_CPU1_PERST1_R_N";
248"FM_CPU1_SLP_S3_N";
249"CPU0_NV_SAVE_N";
250"RST_RT_CPU1_P1_PERST_R_N";
251"RST_CPU1_PERST0_N";
252"RST_RT_CPU1_P0_RESET_R_N";
253"RST_RT_CPU1_P0_PERST_R_N";
254"RST_CPU0_PERST1_N";
255"PWRGD_P0V9_RETIMER_CPU0";
256"FM_CPU1_SLP_S5_N";
257"RST_CPU1_PERST1_N";
258"RST_CPU1_SYS_N";
259"RST_CPU0_SYS_N";
260"TP_SLOT1_CLKREQ_0_R_N";
261"RST_CPU0_PERST1_R_N";
262"RST_RT_CPU1_P0_PERST_R2_N";
263"RST_RT_CPU1_P0_RESET_R2_N";
264"PWRGD_P0V9_RETIMER_CPU1";
265"RST_CPU1_RSMRST_N";
266"RST_CPU1_PERST0_R_N";
267"PWRGD_P0V9_RETIMER_CPU0_R2";
268"FM_CPU1_RSMRST_N";
269"FM_CPU0_RSMRST_N";
270"RST_CPU0_RSMRST_N";
271"PWRGD_P0V9_RETIMER_CPU1_R2";
272"SW_P3V3_EN";
273"GPU_HMC_PRSNT_ISO_N"CDS_PHYS_NET_NAME"GPU_BB_RSVD_1_ISO";
274"GPU_FPGA_THERM_OVERT_ISO_N"CDS_PHYS_NET_NAME"GPU_3V3IO_RSVD0_FFU_ISO";
275"SWB_HSC_PWRGD_ISO"CDS_PHYS_NET_NAME"GPU_3V3IO_RSVD0_FFU_ISO";
276"PRSNT_CABLE_GPU_A1_ISO_R_N"CDS_PHYS_NET_NAME"GPU_3V3IO_RSVD1_ISO_R";
277"GPU_3V3IO_RSVD5_FFU_ISO_R"CDS_PHYS_NET_NAME"GPU_3V3IO_RSVD1_ISO_R";
278"GPU_FPGA_RST_N"CDS_PHYS_NET_NAME"GPU_3V3IO_RSVD1_ISO_R";
279"FM_GPU_PWR_EN"CDS_PHYS_NET_NAME"GPU_3V3IO_RSVD1_ISO_R";
280"FM_PWRGD_PVDDCR_CPU0_P1";
281"FM_PWRGD_PVDDCR_CPU1_P1";
282"FM_PWRGD_PVDD11_S3_P0";
283"GPU_FPGA_EROT_FATALERR_ISO_N"CDS_PHYS_NET_NAME"GPU_BB_RSVD_1_ISO";
284"RST_BMC_FROM_SWB_ISO_N"CDS_PHYS_NET_NAME"GPU_BB_RSVD_1_ISO";
285"FM_SWB_BIC_READY_ISO_N"CDS_PHYS_NET_NAME"SWB_HSC_PWRGD_ISO";
286"FM_GPU_PWRGD_ISO"CDS_PHYS_NET_NAME"SWB_HSC_PWRGD_ISO";
287"GPU_FPGA_BOOT_EN_R"CDS_PHYS_NET_NAME"GPU_3V3IO_RSVD1_ISO_R";
288"PVDD33_S5_EN";
289"PVDD18_S5_P0_EN";
290"PWRGD_P3V3_AUX";
291"FM_PWRGD_P1V8_RETIMER_CPU0"CDS_PHYS_NET_NAME"TP_SPI_PLD_CLK";
292"PVDD18_S5_P1_R_EN";
293"FM_PVDDIO_P1_EN";
294"FM_GPU_HSC_EN_R"CDS_PHYS_NET_NAME"GPU_3V3IO_RSVD1_ISO_R";
295"PRSNT_CABLE_GPU_A2_ISO_R_N"CDS_PHYS_NET_NAME"GPU_3V3IO_RSVD1_ISO_R";
296"FM_PVDD33_S5_EN";
297"CPU0_PWR_GOOD";
298"PVDDIO_P1_EN";
299"PWRGD_PVDDIO_P1";
300"FM_GPU_HSC_EN"CDS_PHYS_NET_NAME"GPU_3V3IO_RSVD1_ISO";
301"HP_LVC3_E1S_0_HSC_PWRGD";
302"FM_NCSI_OCP_SFF_R_OE";
303"FM_SWB_PWRGD_ISO"CDS_PHYS_NET_NAME"SWB_HSC_PWRGD_ISO";
304"FM_SWB_PWRGD_ISO_R"CDS_PHYS_NET_NAME"GPU_3V3IO_RSVD1_ISO_R";
305"RST_PERST_M2_0_N";
306"FM_SMB_1_ALERT_GPU_ISO_N"CDS_PHYS_NET_NAME"SWB_HSC_PWRGD_ISO";
307"BIC_MONITER_ISO"CDS_PHYS_NET_NAME"SWB_HSC_PWRGD_ISO";
308"RST_PERST_CPU1_SWB_N"CDS_PHYS_NET_NAME"GPU_3V3IO_RSVD1_ISO_R";
309"RST_PERST_E1S_0_N";
310"FM_RST_PERST_SCM_N";
311"HGX_DETECT_N"CDS_PHYS_NET_NAME"GPU_3V3IO_RSVD1_ISO";
312"GPU_3V3IO_RSVD3_ISO"CDS_PHYS_NET_NAME"GPU_3V3IO_RSVD1_ISO";
313"GPU_3V3IO_RSVD1_ISO"CDS_PHYS_NET_NAME"GPU_3V3IO_RSVD1_ISO";
314"GPU_3V3IO_RSVD4_ISO_R"CDS_PHYS_NET_NAME"GPU_3V3IO_RSVD1_ISO_R";
315"HGX_DETECT_N_R"CDS_PHYS_NET_NAME"GPU_3V3IO_RSVD1_ISO_R";
316"FM_RST_PERST_SCM_R_N";
317"RST_PERST_E1S_0_R_N";
318"SWB_HSC_EN_R"CDS_PHYS_NET_NAME"GPU_3V3IO_RSVD1_ISO_R";
319"GPU_3V3IO_RSVD0_FFU_ISO_R"CDS_PHYS_NET_NAME"GPU_3V3IO_RSVD1_ISO_R";
320"GPU_3V3IO_RSVD1_FFU_ISO_R"CDS_PHYS_NET_NAME"GPU_3V3IO_RSVD1_ISO_R";
321"RST_PERST_CPU0_SWB_N"CDS_PHYS_NET_NAME"GPU_3V3IO_RSVD1_ISO_R";
322"GPU_FPGA_OVERT_ISO_R_N"CDS_PHYS_NET_NAME"GPU_3V3IO_RSVD1_ISO_R";
323"GPU_WP_HW_CTRL_R_N"CDS_PHYS_NET_NAME"GPU_3V3IO_RSVD1_ISO_R";
324"GPU_PRSNT_N_ISO_R"CDS_PHYS_NET_NAME"GPU_3V3IO_RSVD1_ISO_R";
325"GPU_FPGA_EROT_FATALERR_ISO_R_N"CDS_PHYS_NET_NAME"GPU_3V3IO_RSVD1_ISO_R";
326"BIC_MONITER_ISO_R"CDS_PHYS_NET_NAME"GPU_3V3IO_RSVD1_ISO_R";
327"FM_SMB_2_ALERT_GPU_ISO_R_N"CDS_PHYS_NET_NAME"GPU_3V3IO_RSVD1_ISO_R";
328"P0V9_RETIMER_CPU0_EN";
329"E1S_0_P12V_EN";
330"HPDB_HSC_PWRGD_ISO"CDS_PHYS_NET_NAME"FM_SWB_PWR_EN_R";
331"GPU_BASE_STBY_EN_R"CDS_PHYS_NET_NAME"GPU_3V3IO_RSVD1_ISO_R";
332"PVDDIO_P0_EN";
333"PWRGD_PVDD11_S3_P0";
334"PVDDCR_CPU0_P1_EN";
335"GPU_FPGA_EROT_RECOV_N"CDS_PHYS_NET_NAME"GPU_3V3IO_RSVD1_ISO";
336"BMC_MONITER_R"CDS_PHYS_NET_NAME"GPU_3V3IO_RSVD1_ISO";
337"HP_LVC3_SCM_HSC_PWRGD";
%"Q_RES"
"1","(-6425,4125)","0","pure_quanta","I100";
;
LOCATION"R194"
$SEC"1"
CDS_SEC"1"
VALUE"0"
CDS_LIB"pure_quanta"
PACK_TYPE"0402LF"
TOLERANCE"5%"
MATERIAL"CHIP"
WATTAGE"1/16W"
BOM_COST"MEM"
PART_NUMBER"CS00002JB13";
"B"
$PN"2"130;
"A"
$PN"1"127;
%"Q_RES"
"1","(-6425,4325)","0","pure_quanta","I101";
;
LOCATION"R1281"
$SEC"1"
CDS_SEC"1"
VALUE"33"
CDS_LIB"pure_quanta"
BOM_COST"MEM"
WATTAGE"1/16W"
MATERIAL"CHIP"
TOLERANCE"5%"
PACK_TYPE"0402LF"
PART_NUMBER"CS03302JB10";
"B"
$PN"2"124;
"A"
$PN"1"114;
%"Q_RES"
"1","(-6425,4275)","0","pure_quanta","I102";
;
LOCATION"R1280"
$SEC"1"
CDS_SEC"1"
VALUE"33"
CDS_LIB"pure_quanta"
BOM_COST"MEM"
WATTAGE"1/16W"
MATERIAL"CHIP"
TOLERANCE"5%"
PACK_TYPE"0402LF"
PART_NUMBER"CS03302JB10";
"B"
$PN"2"125;
"A"
$PN"1"113;
%"Q_RES"
"1","(-6425,4475)","0","pure_quanta","I103";
;
LOCATION"R1279"
$SEC"1"
CDS_SEC"1"
VALUE"33"
CDS_LIB"pure_quanta"
BOM_COST"MEM"
WATTAGE"1/16W"
MATERIAL"CHIP"
TOLERANCE"5%"
PACK_TYPE"0402LF"
PART_NUMBER"CS03302JB10";
"B"
$PN"2"197;
"A"
$PN"1"112;
%"Q_RES"
"1","(-6425,4525)","0","pure_quanta","I104";
;
LOCATION"R215"
$SEC"1"
CDS_SEC"1"
VALUE"33"
CDS_LIB"pure_quanta"
BOM_COST"MEM"
WATTAGE"1/16W"
MATERIAL"CHIP"
TOLERANCE"5%"
PACK_TYPE"0402LF"
PART_NUMBER"CS03302JB10";
"B"
$PN"2"196;
"A"
$PN"1"87;
%"Q_RES"
"1","(-6425,4625)","0","pure_quanta","I105";
;
LOCATION"R1278"
$SEC"1"
CDS_SEC"1"
VALUE"33"
CDS_LIB"pure_quanta"
BOM_COST"MEM"
WATTAGE"1/16W"
MATERIAL"CHIP"
TOLERANCE"5%"
PACK_TYPE"0402LF"
PART_NUMBER"CS03302JB10";
"B"
$PN"2"240;
"A"
$PN"1"88;
%"Q_RES"
"1","(-6425,4675)","0","pure_quanta","I106";
;
LOCATION"R203"
$SEC"1"
CDS_SEC"1"
VALUE"0"
BOM_COST"MEM"
CDS_LIB"pure_quanta"
WATTAGE"1/16W"
MATERIAL"CHIP"
TOLERANCE"5%"
PACK_TYPE"0402LF"
PART_NUMBER"CS00002JB13";
"B"
$PN"2"194;
"A"
$PN"1"84;
%"Q_RES"
"1","(-6425,4725)","0","pure_quanta","I107";
;
LOCATION"R371"
$SEC"1"
CDS_SEC"1"
VALUE"33"
CDS_LIB"pure_quanta"
BOM_COST"MEM"
WATTAGE"1/16W"
MATERIAL"CHIP"
TOLERANCE"5%"
PACK_TYPE"0402LF"
PART_NUMBER"CS03302JB10";
"B"
$PN"2"86;
"A"
$PN"1"85;
%"Q_RES"
"1","(-6425,4775)","0","pure_quanta","I108";
;
LOCATION"R219"
$SEC"1"
CDS_SEC"1"
VALUE"33"
CDS_LIB"pure_quanta"
BOM_COST"MEM"
WATTAGE"1/16W"
MATERIAL"CHIP"
TOLERANCE"5%"
PACK_TYPE"0402LF"
PART_NUMBER"CS03302JB10";
"B"
$PN"2"193;
"A"
$PN"1"108;
%"Q_RES"
"1","(-6425,4925)","0","pure_quanta","I109";
;
LOCATION"R196"
$SEC"1"
CDS_SEC"1"
VALUE"0"
CDS_LIB"pure_quanta"
BOM_COST"MEM"
WATTAGE"1/16W"
MATERIAL"CHIP"
TOLERANCE"5%"
PACK_TYPE"0402LF"
PART_NUMBER"CS00002JB13";
"B"
$PN"2"190;
"A"
$PN"1"83;
%"Q_RES"
"1","(-6425,4975)","0","pure_quanta","I110";
;
LOCATION"R242"
$SEC"1"
CDS_SEC"1"
VALUE"0"
BOM_COST"MEM"
CDS_LIB"pure_quanta"
WATTAGE"1/16W"
MATERIAL"CHIP"
TOLERANCE"5%"
PACK_TYPE"0402LF"
PART_NUMBER"CS00002JB13";
"B"
$PN"2"181;
"A"
$PN"1"82;
%"Q_RES"
"1","(-6425,5025)","0","pure_quanta","I111";
;
LOCATION"R159"
$SEC"1"
CDS_SEC"1"
VALUE"33"
CDS_LIB"pure_quanta"
BOM_COST"MEM"
WATTAGE"1/16W"
MATERIAL"CHIP"
TOLERANCE"5%"
PACK_TYPE"0402LF"
PART_NUMBER"CS03302JB10";
"B"
$PN"2"182;
"A"
$PN"1"81;
%"Q_RES"
"1","(-6425,5075)","0","pure_quanta","I112";
;
LOCATION"R463"
$SEC"1"
CDS_SEC"1"
VALUE"33"
CDS_LIB"pure_quanta"
WATTAGE"1/16W"
MATERIAL"CHIP"
TOLERANCE"5%"
PACK_TYPE"0402LF"
PART_NUMBER"CS03302JB10";
"B"
$PN"2"189;
"A"
$PN"1"109;
%"Q_RES"
"1","(-6425,5125)","0","pure_quanta","I113";
;
LOCATION"R57"
$SEC"1"
CDS_SEC"1"
VALUE"0"
CDS_LIB"pure_quanta"
BOM_COST"MEM"
WATTAGE"1/16W"
MATERIAL"CHIP"
TOLERANCE"5%"
PACK_TYPE"0402LF"
PART_NUMBER"CS00002JB13";
"B"
$PN"2"188;
"A"
$PN"1"110;
%"Q_RES"
"1","(-6425,5175)","0","pure_quanta","I114";
;
LOCATION"R241"
$SEC"1"
CDS_SEC"1"
VALUE"0"
BOM_COST"MEM"
CDS_LIB"pure_quanta"
WATTAGE"1/16W"
MATERIAL"CHIP"
TOLERANCE"5%"
PACK_TYPE"0402LF"
PART_NUMBER"CS00002JB13";
"B"
$PN"2"180;
"A"
$PN"1"242;
%"Q_RES"
"1","(-6425,5375)","0","pure_quanta","I115";
;
LOCATION"R272"
$SEC"1"
CDS_SEC"1"
VALUE"0"
MATERIAL"EMPTY"
CDS_LIB"pure_quanta"
BOM_COST"MEM"
WATTAGE"1/16W"
TOLERANCE"5%"
PACK_TYPE"0402LF"
PART_NUMBER"CS00002JB13";
"B"
$PN"2"186;
"A"
$PN"1"258;
%"Q_RES"
"1","(-6425,5325)","0","pure_quanta","I116";
;
LOCATION"R253"
$SEC"1"
CDS_SEC"1"
VALUE"0"
BOM_COST"MEM"
CDS_LIB"pure_quanta"
WATTAGE"1/16W"
MATERIAL"CHIP"
TOLERANCE"5%"
PACK_TYPE"0402LF"
PART_NUMBER"CS00002JB13";
"B"
$PN"2"185;
"A"
$PN"1"249;
%"Q_RES"
"1","(-6425,5425)","0","pure_quanta","I117";
;
LOCATION"R216"
$SEC"1"
CDS_SEC"1"
VALUE"33"
BOM_COST"MEM"
CDS_LIB"pure_quanta"
WATTAGE"1/16W"
MATERIAL"CHIP"
TOLERANCE"5%"
PACK_TYPE"0402LF"
PART_NUMBER"CS03302JB10";
"B"
$PN"2"187;
"A"
$PN"1"259;
%"Q_RES"
"1","(-6425,5525)","0","pure_quanta","I118";
;
LOCATION"R217"
$SEC"1"
CDS_SEC"1"
VALUE"33"
BOM_COST"MEM"
CDS_LIB"pure_quanta"
WATTAGE"1/16W"
MATERIAL"CHIP"
TOLERANCE"5%"
PACK_TYPE"0402LF"
PART_NUMBER"CS03302JB10";
"B"
$PN"2"269;
"A"
$PN"1"270;
%"Q_RES"
"1","(-6425,5575)","0","pure_quanta","I119";
;
LOCATION"R273"
$SEC"1"
CDS_SEC"1"
VALUE"33"
BOM_COST"MEM"
CDS_LIB"pure_quanta"
WATTAGE"1/16W"
MATERIAL"CHIP"
TOLERANCE"5%"
PACK_TYPE"0402LF"
PART_NUMBER"CS03302JB10";
"B"
$PN"2"268;
"A"
$PN"1"265;
%"Q_RES"
"1","(-6425,5675)","0","pure_quanta","I120";
;
LOCATION"R197"
$SEC"1"
CDS_SEC"1"
VALUE"0"
CDS_LIB"pure_quanta"
BOM_COST"MEM"
WATTAGE"1/16W"
MATERIAL"CHIP"
TOLERANCE"5%"
PACK_TYPE"0402LF"
PART_NUMBER"CS00002JB13";
"B"
$PN"2"266;
"A"
$PN"1"251;
%"Q_RES"
"1","(-6425,5825)","0","pure_quanta","I121";
;
LOCATION"R255"
$SEC"1"
CDS_SEC"1"
VALUE"0"
CDS_LIB"pure_quanta"
PACK_TYPE"0402LF"
TOLERANCE"5%"
MATERIAL"CHIP"
WATTAGE"1/16W"
BOM_COST"MEM"
PART_NUMBER"CS00002JB13";
"B"
$PN"2"261;
"A"
$PN"1"254;
%"Q_RES"
"1","(-6425,6025)","0","pure_quanta","I122";
;
LOCATION"R198"
$SEC"1"
CDS_SEC"1"
VALUE"0"
CDS_LIB"pure_quanta"
BOM_COST"MEM"
WATTAGE"1/16W"
MATERIAL"CHIP"
TOLERANCE"5%"
PACK_TYPE"0402LF"
PART_NUMBER"CS00002JB13";
"B"
$PN"2"247;
"A"
$PN"1"257;
%"Q_RES"
"1","(-6425,6075)","0","pure_quanta","I123";
;
LOCATION"R254"
$SEC"1"
CDS_SEC"1"
VALUE"0"
CDS_LIB"pure_quanta"
BOM_COST"MEM"
WATTAGE"1/16W"
MATERIAL"CHIP"
TOLERANCE"5%"
PACK_TYPE"0402LF"
PART_NUMBER"CS00002JB13";
"B"
$PN"2"246;
"A"
$PN"1"243;
%"Q_RES"
"1","(-2300,1625)","0","pure_quanta","I125";
;
LOCATION"R798"
$SEC"1"
CDS_SEC"1"
VALUE"33"
CDS_LIB"pure_quanta"
BOM_COST"MEM"
WATTAGE"1/16W"
MATERIAL"CHIP"
TOLERANCE"5%"
PACK_TYPE"0402LF"
PART_NUMBER"CS03302JB10";
"B"
$PN"2"305;
"A"
$PN"1"91;
%"Q_RES"
"1","(-3225,3825)","0","pure_quanta","I126";
;
LOCATION"R265"
$SEC"1"
CDS_SEC"1"
VALUE"33"
CDS_LIB"pure_quanta"
BOM_COST"MEM"
WATTAGE"1/16W"
MATERIAL"CHIP"
TOLERANCE"5%"
PACK_TYPE"0402LF"
PART_NUMBER"CS03302JB10";
"B"
$PN"2"77;
"A"
$PN"1"74;
%"Q_RES"
"1","(-3225,3875)","0","pure_quanta","I127";
;
LOCATION"R1202"
$SEC"1"
CDS_SEC"1"
VALUE"0"
CDS_LIB"pure_quanta"
PACK_TYPE"0402LF"
TOLERANCE"5%"
MATERIAL"CHIP"
WATTAGE"1/16W"
BOM_COST"MEM"
PART_NUMBER"CS00002JB13";
"B"
$PN"2"76;
"A"
$PN"1"75;
%"Q_RES"
"1","(-3225,4075)","0","pure_quanta","I128";
;
LOCATION"R252"
$SEC"1"
CDS_SEC"1"
VALUE"0"
CDS_LIB"pure_quanta"
BOM_COST"MEM"
WATTAGE"1/16W"
MATERIAL"CHIP"
TOLERANCE"5%"
PACK_TYPE"0402LF"
PART_NUMBER"CS00002JB13";
"B"
$PN"2"79;
"A"
$PN"1"165;
%"Q_RES"
"1","(-3225,4025)","0","pure_quanta","I129";
;
LOCATION"R186"
$SEC"1"
CDS_SEC"1"
VALUE"33"
PACK_TYPE"0402LF"
TOLERANCE"5%"
MATERIAL"CHIP"
WATTAGE"1/16W"
BOM_COST"MEM"
CDS_LIB"pure_quanta"
PART_NUMBER"CS03302JB10";
"B"
$PN"2"80;
"A"
$PN"1"166;
%"Q_RES"
"1","(-2300,2775)","0","pure_quanta","I130";
;
LOCATION"R957"
$SEC"1"
CDS_SEC"1"
VALUE"33"
CDS_LIB"pure_quanta"
BOM_COST"MEM"
WATTAGE"1/16W"
MATERIAL"CHIP"
TOLERANCE"5%"
PACK_TYPE"0402LF"
PART_NUMBER"CS03302JB10";
"B"
$PN"2"310;
"A"
$PN"1"316;
%"Q_RES"
"1","(-2300,2725)","0","pure_quanta","I131";
;
LOCATION"R685"
$SEC"1"
CDS_SEC"1"
VALUE"33"
BOM_COST"MEM"
CDS_LIB"pure_quanta"
WATTAGE"1/16W"
MATERIAL"CHIP"
TOLERANCE"5%"
PACK_TYPE"0402LF"
PART_NUMBER"CS03302JB10";
"B"
$PN"2"309;
"A"
$PN"1"317;
%"Q_RES"
"1","(-3225,4175)","0","pure_quanta","I154";
;
LOCATION"R158"
$SEC"1"
CDS_SEC"1"
VALUE"33"
PACK_TYPE"0402LF"
TOLERANCE"5%"
MATERIAL"CHIP"
WATTAGE"1/16W"
BOM_COST"MEM"
CDS_LIB"pure_quanta"
PART_NUMBER"CS03302JB10";
"B"
$PN"2"120;
"A"
$PN"1"202;
%"Q_RES"
"1","(-3225,4225)","0","pure_quanta","I155";
;
LOCATION"R395"
$SEC"1"
CDS_SEC"1"
VALUE"0"
PACK_TYPE"0402LF"
TOLERANCE"5%"
MATERIAL"CHIP"
WATTAGE"1/16W"
BOM_COST"MEM"
CDS_LIB"pure_quanta"
PART_NUMBER"CS00002JB13";
"B"
$PN"2"119;
"A"
$PN"1"162;
%"Q_RES"
"1","(-3225,4325)","0","pure_quanta","I156";
;
LOCATION"R1564"
$SEC"1"
CDS_SEC"1"
VALUE"33"
PACK_TYPE"0402LF"
TOLERANCE"5%"
MATERIAL"CHIP"
WATTAGE"1/16W"
BOM_COST"MEM"
CDS_LIB"pure_quanta"
PART_NUMBER"CS03302JB10";
"B"
$PN"2"164;
"A"
$PN"1"201;
%"Q_RES"
"1","(-3225,4275)","0","pure_quanta","I157";
;
LOCATION"R1616"
$SEC"1"
CDS_SEC"1"
VALUE"33"
PACK_TYPE"0402LF"
TOLERANCE"5%"
MATERIAL"CHIP"
WATTAGE"1/16W"
BOM_COST"MEM"
CDS_LIB"pure_quanta"
PART_NUMBER"CS03302JB10";
"B"
$PN"2"160;
"A"
$PN"1"198;
%"Q_RES"
"1","(-3225,4375)","0","pure_quanta","I158";
;
LOCATION"R1359"
$SEC"1"
CDS_SEC"1"
VALUE"0"
BOM_COST"MEM"
CDS_LIB"pure_quanta"
WATTAGE"1/16W"
MATERIAL"CHIP"
TOLERANCE"5%"
PACK_TYPE"0402LF"
PART_NUMBER"CS00002JB13";
"B"
$PN"2"163;
"A"
$PN"1"200;
%"Q_RES"
"1","(-3225,4475)","0","pure_quanta","I159";
;
LOCATION"R372"
$SEC"1"
CDS_SEC"1"
VALUE"33"
PACK_TYPE"0402LF"
TOLERANCE"5%"
MATERIAL"CHIP"
WATTAGE"1/16W"
BOM_COST"MEM"
CDS_LIB"pure_quanta"
PART_NUMBER"CS03302JB10";
"B"
$PN"2"159;
"A"
$PN"1"156;
%"Q_RES"
"1","(-3225,4575)","0","pure_quanta","I160";
;
LOCATION"R174"
$SEC"1"
CDS_SEC"1"
VALUE"33"
CDS_LIB"pure_quanta"
BOM_COST"MEM"
WATTAGE"1/16W"
MATERIAL"CHIP"
TOLERANCE"5%"
PACK_TYPE"0402LF"
PART_NUMBER"CS03302JB10";
"B"
$PN"2"167;
"A"
$PN"1"211;
%"Q_RES"
"1","(-3225,4625)","0","pure_quanta","I161";
;
LOCATION"R161"
$SEC"1"
CDS_SEC"1"
VALUE"33"
CDS_LIB"pure_quanta"
BOM_COST"MEM"
WATTAGE"1/16W"
MATERIAL"CHIP"
TOLERANCE"5%"
PACK_TYPE"0402LF"
PART_NUMBER"CS03302JB10";
"B"
$PN"2"168;
"A"
$PN"1"212;
%"Q_RES"
"1","(-3225,4725)","0","pure_quanta","I162";
;
LOCATION"R251"
$SEC"1"
CDS_SEC"1"
VALUE"0"
CDS_LIB"pure_quanta"
BOM_COST"MEM"
WATTAGE"1/16W"
MATERIAL"CHIP"
TOLERANCE"5%"
PACK_TYPE"0402LF"
PART_NUMBER"CS00002JB13";
"B"
$PN"2"158;
"A"
$PN"1"154;
%"Q_RES"
"1","(-3225,4675)","0","pure_quanta","I163";
;
LOCATION"R173"
$SEC"1"
CDS_SEC"1"
VALUE"33"
BOM_COST"MEM"
CDS_LIB"pure_quanta"
WATTAGE"1/16W"
MATERIAL"CHIP"
TOLERANCE"5%"
PACK_TYPE"0402LF"
PART_NUMBER"CS03302JB10";
"B"
$PN"2"157;
"A"
$PN"1"213;
%"Q_RES"
"1","(-3225,4825)","0","pure_quanta","I164";
;
LOCATION"R588"
$SEC"1"
CDS_SEC"1"
VALUE"33"
CDS_LIB"pure_quanta"
BOM_COST"MEM"
WATTAGE"1/16W"
MATERIAL"CHIP"
TOLERANCE"5%"
PACK_TYPE"0402LF"
PART_NUMBER"CS03302JB10";
"B"
$PN"2"170;
"A"
$PN"1"214;
%"Q_RES"
"1","(-3225,4925)","0","pure_quanta","I165";
;
LOCATION"R277"
$SEC"1"
CDS_SEC"1"
VALUE"33"
BOM_COST"MEM"
CDS_LIB"pure_quanta"
WATTAGE"1/16W"
MATERIAL"CHIP"
TOLERANCE"5%"
PACK_TYPE"0402LF"
PART_NUMBER"CS03302JB10";
"B"
$PN"2"155;
"A"
$PN"1"139;
%"Q_RES"
"1","(-3225,5025)","0","pure_quanta","I166";
;
LOCATION"R937"
$SEC"1"
CDS_SEC"1"
VALUE"0"
CDS_LIB"pure_quanta"
BOM_COST"MEM"
WATTAGE"1/16W"
MATERIAL"CHIP"
TOLERANCE"5%"
PACK_TYPE"0402LF"
PART_NUMBER"CS00002JB13";
"B"
$PN"2"140;
"A"
$PN"1"234;
%"Q_RES"
"1","(-3225,5075)","0","pure_quanta","I167";
;
LOCATION"R856"
$SEC"1"
CDS_SEC"1"
VALUE"0"
CDS_LIB"pure_quanta"
BOM_COST"MEM"
WATTAGE"1/16W"
MATERIAL"CHIP"
TOLERANCE"5%"
PACK_TYPE"0402LF"
PART_NUMBER"CS00002JB13";
"B"
$PN"2"174;
"A"
$PN"1"233;
%"Q_RES"
"1","(-3225,5125)","0","pure_quanta","I168";
;
LOCATION"R708"
$SEC"1"
CDS_SEC"1"
VALUE"33"
CDS_LIB"pure_quanta"
BOM_COST"MEM"
WATTAGE"1/16W"
MATERIAL"CHIP"
TOLERANCE"5%"
PACK_TYPE"0402LF"
PART_NUMBER"CS03302JB10";
"B"
$PN"2"141;
"A"
$PN"1"232;
%"Q_RES"
"1","(-3225,5225)","0","pure_quanta","I169";
;
LOCATION"R1551"
$SEC"1"
CDS_SEC"1"
VALUE"33"
PACK_TYPE"0402LF"
TOLERANCE"5%"
MATERIAL"CHIP"
WATTAGE"1/16W"
BOM_COST"MEM"
CDS_LIB"pure_quanta"
PART_NUMBER"CS03302JB10";
"B"
$PN"2"143;
"A"
$PN"1"226;
%"Q_RES"
"1","(-3225,5175)","0","pure_quanta","I170";
;
LOCATION"R1552"
$SEC"1"
CDS_SEC"1"
VALUE"33"
PACK_TYPE"0402LF"
TOLERANCE"5%"
MATERIAL"CHIP"
WATTAGE"1/16W"
BOM_COST"MEM"
CDS_LIB"pure_quanta"
PART_NUMBER"CS03302JB10";
"B"
$PN"2"142;
"A"
$PN"1"227;
%"Q_RES"
"1","(-3225,5275)","0","pure_quanta","I171";
;
LOCATION"R1550"
$SEC"1"
CDS_SEC"1"
VALUE"33"
PACK_TYPE"0402LF"
TOLERANCE"5%"
MATERIAL"CHIP"
WATTAGE"1/16W"
BOM_COST"MEM"
CDS_LIB"pure_quanta"
PART_NUMBER"CS03302JB10";
"B"
$PN"2"144;
"A"
$PN"1"225;
%"Q_RES"
"1","(-3225,5375)","0","pure_quanta","I172";
;
LOCATION"R1558"
$SEC"1"
CDS_SEC"1"
VALUE"33"
CDS_LIB"pure_quanta"
PACK_TYPE"0402LF"
TOLERANCE"5%"
MATERIAL"CHIP"
WATTAGE"1/16W"
PART_NUMBER"CS03302JB10";
"B"
$PN"2"153;
"A"
$PN"1"137;
%"Q_RES"
"1","(-3225,5325)","0","pure_quanta","I173";
;
LOCATION"R1549"
$SEC"1"
CDS_SEC"1"
VALUE"33"
CDS_LIB"pure_quanta"
BOM_COST"MEM"
WATTAGE"1/16W"
MATERIAL"CHIP"
TOLERANCE"5%"
PACK_TYPE"0402LF"
PART_NUMBER"CS03302JB10";
"B"
$PN"2"138;
"A"
$PN"1"224;
%"Q_RES"
"1","(-3225,5475)","0","pure_quanta","I174";
;
LOCATION"R1553"
$SEC"1"
CDS_SEC"1"
VALUE"33"
WATTAGE"1/16W"
MATERIAL"CHIP"
TOLERANCE"5%"
PACK_TYPE"0402LF"
CDS_LIB"pure_quanta"
PART_NUMBER"CS03302JB10";
"B"
$PN"2"151;
"A"
$PN"1"223;
%"Q_RES"
"1","(-3225,5425)","0","pure_quanta","I175";
;
LOCATION"R1557"
$SEC"1"
CDS_SEC"1"
VALUE"33"
WATTAGE"1/16W"
MATERIAL"CHIP"
TOLERANCE"5%"
PACK_TYPE"0402LF"
CDS_LIB"pure_quanta"
PART_NUMBER"CS03302JB10";
"B"
$PN"2"152;
"A"
$PN"1"136;
%"Q_RES"
"1","(-3225,5525)","0","pure_quanta","I176";
;
LOCATION"R1556"
$SEC"1"
CDS_SEC"1"
VALUE"33"
CDS_LIB"pure_quanta"
PACK_TYPE"0402LF"
TOLERANCE"5%"
MATERIAL"CHIP"
WATTAGE"1/16W"
PART_NUMBER"CS03302JB10";
"B"
$PN"2"175;
"A"
$PN"1"231;
%"Q_RES"
"1","(-3225,5725)","0","pure_quanta","I177";
;
LOCATION"R258"
$SEC"1"
CDS_SEC"1"
VALUE"0"
CDS_LIB"pure_quanta"
PACK_TYPE"0402LF"
TOLERANCE"5%"
MATERIAL"CHIP"
WATTAGE"1/16W"
BOM_COST"MEM"
PART_NUMBER"CS00002JB13";
"B"
$PN"2"177;
"A"
$PN"1"179;
%"Q_RES"
"1","(-3225,5775)","0","pure_quanta","I178";
;
LOCATION"R1203"
$SEC"1"
CDS_SEC"1"
VALUE"33"
PACK_TYPE"0402LF"
TOLERANCE"5%"
MATERIAL"CHIP"
WATTAGE"1/16W"
BOM_COST"MEM"
CDS_LIB"pure_quanta"
PART_NUMBER"CS03302JB10";
"B"
$PN"2"178;
"A"
$PN"1"228;
%"Q_RES"
"1","(-3225,5925)","0","pure_quanta","I179";
;
LOCATION"R193"
$SEC"1"
CDS_SEC"1"
VALUE"0"
BOM_COST"MEM"
WATTAGE"1/16W"
MATERIAL"CHIP"
TOLERANCE"5%"
PACK_TYPE"0402LF"
CDS_LIB"pure_quanta"
PART_NUMBER"CS00002JB13";
"B"
$PN"2"216;
"A"
$PN"1"149;
%"Q_RES"
"1","(-3225,6125)","0","pure_quanta","I180";
;
LOCATION"R250"
$SEC"1"
CDS_SEC"1"
VALUE"0"
CDS_LIB"pure_quanta"
BOM_COST"MEM"
WATTAGE"1/16W"
MATERIAL"CHIP"
TOLERANCE"5%"
PACK_TYPE"0402LF"
PART_NUMBER"CS00002JB13";
"B"
$PN"2"135;
"A"
$PN"1"241;
%"Q_RES"
"1","(-3225,6175)","0","pure_quanta","I215";
;
LOCATION"R933"
$SEC"1"
CDS_SEC"1"
VALUE"33"
CDS_LIB"pure_quanta"
BOM_COST"MEM"
WATTAGE"1/16W"
MATERIAL"CHIP"
TOLERANCE"5%"
PACK_TYPE"0402LF"
PART_NUMBER"CS03302JB10";
"B"
$PN"2"134;
"A"
$PN"1"150;
%"LCMXO3LF9400C5BG484C"
"2","(-4500,1850)","0","pure_quanta","I216";
;
LOCATION"U18"
$SEC"2"
CDS_SEC"2"
VALUE"LCMXO3LF-9400C-5BG484C"
PART_TYPE"SMLF"
MATERIAL"IC"
CDS_LIB"pure_quanta"
NEEDS_NO_SIZE"TRUE"
CDS_LMAN_SYM_OUTLINE"-725,1375,725,-1375"
PART_NUMBER"AJ094000T08";
"PB21D"
$PN"Y10"14;
"PB21C"
$PN"Y9"18;
"PB46D"
$PN"T16"43;
"PB46C"
$PN"V17"44;
"PB44D"
$PN"W18"46;
"PB44C"
$PN"Y19"331;
"PB43D"
$PN"U16"49;
"PB43C"
$PN"T15"287;
"PB41D"
$PN"W17"51;
"PB41C"
$PN"Y18"327;
"PB41B"
$PN"AA18"92;
"PB41A"
$PN"AB18"304;
"PB40D"
$PN"V16"91;
"PB40C"
$PN"Y17"272;
"PB40B"
$PN"AA17"73;
"PB40A"
$PN"AB17"71;
"PB38D"
$PN"U15"72;
"PB38C"
$PN"V15"326;
"PB38B"
$PN"AA16"325;
"PB38A"
$PN"AB16"324;
"PB35D"
$PN"W15"323;
"PB35C"
$PN"Y15"322;
"PB32D"
$PN"V14"295;
"PB32C"
$PN"U14"308;
"PB32B"
$PN"T14"321;
"PB32A"
$PN"T13"320;
"PB33D"
$PN"W14"106;
"PB33C"
$PN"Y14"105;
"PB30D"
$PN"W13"319;
"PB30C"
$PN"Y13"318;
"PB29D"
$PN"U13"315;
"PB29C"
$PN"V13"314;
"PB27D"
$PN"V12"6;
"PB27C"
$PN"U12"0;
"PB27B"
$PN"T12"7;
"PB27A"
$PN"Y12"8;
"PB22D"
$PN"U11"4;
"PB22C"
$PN"T11"12;
"PB19D"
$PN"U10"20;
"PB19C"
$PN"T10"294;
"PB19B"
$PN"AB9"16;
"PB19A"
$PN"AA9"293;
"PB18D"
$PN"W9"21;
"PB18C"
$PN"Y8"22;
"PB16D"
$PN"W8"24;
"PB16C"
$PN"V9"296;
"PB13B"
$PN"AB7"27;
"PB13A"
$PN"AA7"28;
"PB11D"
$PN"V7"278;
"PB11C"
$PN"W6"279;
"PB11B"
$PN"AB6"29;
"PB11A"
$PN"AA6"30;
"PB35B"
$PN"AA15"103;
"PB35A"
$PN"AB15"107;
"PB46B||SI||SISPI"
$PN"AA21"45;
"PB46A||SN"
$PN"AB21"54;
"PB44B"
$PN"AA20"47;
"PB44A"
$PN"AB20"48;
"PB43B"
$PN"AA19"42;
"PB43A"
$PN"AB19"93;
"PB33B"
$PN"AA14"276;
"PB33A"
$PN"AB14"277;
"PB30B"
$PN"AA13"317;
"PB30A"
$PN"AB13"316;
"PB29B||PCLKC2_1"
$PN"AA12"203;
"PB29A||PCLKT2_1"
$PN"AB12"204;
"PB24D"
$PN"Y11"9;
"PB24C"
$PN"V11"5;
"PB24B"
$PN"AB11"10;
"PB24A"
$PN"AA11"11;
"PB22B||PCLKC2_0"
$PN"AB10"3;
"PB22A||PCLKT2_0"
$PN"AA10"13;
"PB21B"
$PN"W10"19;
"PB21A"
$PN"V10"15;
"PB18B"
$PN"AB8"17;
"PB18A"
$PN"AA8"23;
"PB16B||SO||SPISO"
$PN"U9"25;
"PB16A||MCLK||CCLK"
$PN"T9"291;
"PB13D"
$PN"U8"26;
"PB13C"
$PN"V8"292;
"PB10D"
$PN"Y6"31;
"PB10C"
$PN"Y5"280;
"PB10B"
$PN"AB5"32;
"PB10A"
$PN"AA5"33;
"PB8B"
$PN"AB4"35;
"PB8A"
$PN"AA4"36;
"PB8D"
$PN"T8"281;
"PB8C"
$PN"U7"34;
"PB7D"
$PN"W5"37;
"PB7C"
$PN"Y4"282;
"PB7B"
$PN"AB3"38;
"PB7A||CSSPIN"
$PN"AA3"39;
"PB5D"
$PN"U6"40;
"PB5C"
$PN"V6"41;
"PB5B"
$PN"AB2"65;
"PB5A"
$PN"AA2"70;
%"LCMXO3LF9400C5BG484C"
"7","(-4825,5000)","0","pure_quanta","I217";
;
LOCATION"U18"
$SEC"7"
CDS_SEC"7"
PART_TYPE"SMLF"
MATERIAL"IC"
VALUE"LCMXO3LF-9400C-5BG484C"
CDS_LIB"pure_quanta"
NEEDS_NO_SIZE"TRUE"
CDS_LMAN_SYM_OUTLINE"-475,1275,475,-1275"
PART_NUMBER"AJ094000T08";
"PR30D"
$PN"Y20"207;
"PR30C"
$PN"W19"74;
"PR28D"
$PN"U18"202;
"PR28C"
$PN"U19"162;
"PR28B"
$PN"W21"198;
"PR28A"
$PN"Y22"201;
"PR27D"
$PN"U20"200;
"PR27C"
$PN"T17"199;
"PR27B"
$PN"T18"156;
"PR27A"
$PN"T19"210;
"PR26D"
$PN"T20"211;
"PR26C"
$PN"R16"212;
"PR26B"
$PN"R17"213;
"PR26A"
$PN"R18"154;
"PR25D"
$PN"R19"214;
"PR25C"
$PN"R20"236;
"PR24D"
$PN"U21"234;
"PR24C"
$PN"U22"233;
"PR24B"
$PN"P16"232;
"PR24A"
$PN"P17"227;
"PR21D"
$PN"P18"226;
"PR21C"
$PN"P19"225;
"PR21B"
$PN"T21"224;
"PR21A"
$PN"T22"137;
"PR20D"
$PN"P20"136;
"PR20C"
$PN"P22"223;
"PR19D"
$PN"N19"230;
"PR19C"
$PN"N20"229;
"PR18D"
$PN"N18"221;
"PR18C"
$PN"N17"215;
"PR18B"
$PN"N16"149;
"PR18A"
$PN"M16"217;
"PR17D"
$PN"M19"218;
"PR17C"
$PN"M20"219;
"PR16D"
$PN"M17"131;
"PR16C"
$PN"L22"145;
"PR14D"
$PN"L20"128;
"PR14C"
$PN"L19"147;
"PR13D"
$PN"K16"126;
"PR13C"
$PN"K17"125;
"PR13B"
$PN"K18"124;
"PR13A"
$PN"K19"123;
"PR12D"
$PN"K20"122;
"PR12C"
$PN"J20"197;
"PR12B"
$PN"J22"196;
"PR12A"
$PN"J21"195;
"PR11D"
$PN"J19"240;
"PR11C"
$PN"J18"194;
"PR11B"
$PN"J17"86;
"PR11A"
$PN"J16"193;
"PR10D"
$PN"H16"192;
"PR10C"
$PN"H17"191;
"PR10B"
$PN"H18"190;
"PR10A"
$PN"H19"181;
"PR7D"
$PN"H20"182;
"PR7C"
$PN"G17"189;
"PR6D"
$PN"G18"183;
"PR6C"
$PN"G19"184;
"PR6B"
$PN"G20"185;
"PR6A"
$PN"G21"186;
"PR5D"
$PN"F19"187;
"PR5C"
$PN"F18"260;
"PR5B"
$PN"G22"269;
"PR5A"
$PN"F22"268;
"PR4B"
$PN"E21"263;
"PR4A"
$PN"E22"262;
"PR4D"
$PN"E20"271;
"PR4C"
$PN"E19"266;
"PR3D"
$PN"D20"261;
"PR3C"
$PN"D19"267;
"PR2D"
$PN"G16"247;
"PR2C"
$PN"F17"246;
"PR2A||R_GPLLT_FB"
$PN"C21"244;
"PR2B||R_GPLLC_FB"
$PN"C22"245;
"PR3A||R_GPLLT_IN"
$PN"D22"256;
"PR3B||R_GPLLC_IN"
$PN"D21"248;
"PR7A"
$PN"H22"180;
"PR7B"
$PN"H21"188;
"PR14A"
$PN"L17"148;
"PR14B"
$PN"L16"130;
"PR16A"
$PN"K22"132;
"PR16B"
$PN"L21"146;
"PR17A||PCLKT1_0"
$PN"M22"150;
"PR17B||PCLKC1_0"
$PN"M21"241;
"PR19A"
$PN"N22"228;
"PR19B"
$PN"P21"179;
"PR20A"
$PN"R22"222;
"PR20B"
$PN"R21"231;
"PR25A"
$PN"V22"235;
"PR25B"
$PN"W22"139;
"PR29A"
$PN"AA22"161;
"PR29C"
$PN"U17"166;
"PR29B"
$PN"Y21"165;
"PR29D"
$PN"V19"209;
"PR30A"
$PN"V18"208;
"PR30B"
$PN"W20"75;
%"Q_RES"
"1","(-6725,925)","0","pure_quanta","I22";
;
LOCATION"R199"
$SEC"1"
CDS_SEC"1"
VALUE"33"
BOM_COST"MEM"
CDS_LIB"pure_quanta"
WATTAGE"1/16W"
MATERIAL"CHIP"
TOLERANCE"5%"
PACK_TYPE"0402LF"
PART_NUMBER"CS03302JB10";
"B"
$PN"2"11;
"A"
$PN"1"329;
%"Q_RES"
"1","(-2300,2975)","0","pure_quanta","I220";
;
LOCATION"R4170"
$SEC"1"
CDS_SEC"1"
TOLERANCE"1%"
MATERIAL"CHIP"
VALUE"33.2"
WATTAGE"1/16W"
PACK_TYPE"0402LF"
CDS_LIB"pure_quanta"
PART_NUMBER"CS03322FB03";
"B"
$PN"2"313;
"A"
$PN"1"204;
%"Q_RES"
"1","(-2300,2925)","0","pure_quanta","I223";
;
LOCATION"R4171"
$SEC"1"
CDS_SEC"1"
MATERIAL"CHIP"
TOLERANCE"1%"
VALUE"33.2"
CDS_LIB"pure_quanta"
PACK_TYPE"0402LF"
WATTAGE"1/16W"
PART_NUMBER"CS03322FB03";
"B"
$PN"2"312;
"A"
$PN"1"203;
%"Q_RES"
"1","(-2300,2875)","0","pure_quanta","I224";
;
LOCATION"R4172"
$SEC"1"
CDS_SEC"1"
MATERIAL"CHIP"
VALUE"33.2"
TOLERANCE"1%"
CDS_LIB"pure_quanta"
PACK_TYPE"0402LF"
WATTAGE"1/16W"
PART_NUMBER"CS03322FB03";
"B"
$PN"2"69;
"A"
$PN"1"314;
%"Q_RES"
"1","(-2300,2825)","0","pure_quanta","I226";
;
LOCATION"R4556"
$SEC"1"
CDS_SEC"1"
MATERIAL"CHIP"
VALUE"33.2"
TOLERANCE"1%"
CDS_LIB"pure_quanta"
PACK_TYPE"0402LF"
WATTAGE"1/16W"
PART_NUMBER"CS03322FB03";
"B"
$PN"2"311;
"A"
$PN"1"315;
%"Q_RES"
"1","(-2300,2675)","0","pure_quanta","I228";
;
LOCATION"R4558"
$SEC"1"
CDS_SEC"1"
VALUE"33.2"
MATERIAL"CHIP"
TOLERANCE"1%"
CDS_LIB"pure_quanta"
PACK_TYPE"0402LF"
WATTAGE"1/16W"
PART_NUMBER"CS03322FB03";
"B"
$PN"2"94;
"A"
$PN"1"318;
%"Q_RES"
"1","(-2300,2625)","0","pure_quanta","I231";
;
LOCATION"R4143"
$SEC"1"
CDS_SEC"1"
TOLERANCE"1%"
VALUE"33.2"
MATERIAL"CHIP"
CDS_LIB"pure_quanta"
PACK_TYPE"0402LF"
WATTAGE"1/16W"
PART_NUMBER"CS03322FB03";
"B"
$PN"2"96;
"A"
$PN"1"319;
%"Q_RES"
"1","(-2300,2575)","0","pure_quanta","I233";
;
LOCATION"R4144"
$SEC"1"
CDS_SEC"1"
VALUE"33.2"
TOLERANCE"1%"
MATERIAL"CHIP"
WATTAGE"1/16W"
PACK_TYPE"0402LF"
CDS_LIB"pure_quanta"
PART_NUMBER"CS03322FB03";
"B"
$PN"2"100;
"A"
$PN"1"320;
%"Q_RES"
"1","(-2300,2425)","0","pure_quanta","I240";
;
LOCATION"R4147"
$SEC"1"
CDS_SEC"1"
TOLERANCE"1%"
VALUE"33.2"
MATERIAL"CHIP"
CDS_LIB"pure_quanta"
PACK_TYPE"0402LF"
WATTAGE"1/16W"
PART_NUMBER"CS03322FB03";
"B"
$PN"2"99;
"A"
$PN"1"295;
%"Q_RES"
"1","(-2300,2375)","0","pure_quanta","I242";
;
LOCATION"R4148"
$SEC"1"
CDS_SEC"1"
TOLERANCE"1%"
VALUE"33.2"
MATERIAL"CHIP"
CDS_LIB"pure_quanta"
PACK_TYPE"0402LF"
WATTAGE"1/16W"
PART_NUMBER"CS03322FB03";
"B"
$PN"2"101;
"A"
$PN"1"277;
%"Q_RES"
"1","(-2300,2275)","0","pure_quanta","I243";
;
LOCATION"R4563"
$SEC"1"
CDS_SEC"1"
TOLERANCE"1%"
MATERIAL"CHIP"
VALUE"33.2"
WATTAGE"1/16W"
PACK_TYPE"0402LF"
CDS_LIB"pure_quanta"
PART_NUMBER"CS03322FB03";
"B"
$PN"2"275;
"A"
$PN"1"105;
%"Q_RES"
"1","(-2300,2325)","0","pure_quanta","I246";
;
LOCATION"R4157"
$SEC"1"
CDS_SEC"1"
VALUE"33.2"
TOLERANCE"1%"
MATERIAL"CHIP"
WATTAGE"1/16W"
PACK_TYPE"0402LF"
CDS_LIB"pure_quanta"
PART_NUMBER"CS03322FB03";
"B"
$PN"2"104;
"A"
$PN"1"276;
%"Q_RES"
"1","(-2300,2175)","0","pure_quanta","I247";
;
LOCATION"R3480"
$SEC"1"
CDS_SEC"1"
MATERIAL"CHIP"
TOLERANCE"1%"
VALUE"33.2"
CDS_LIB"pure_quanta"
PACK_TYPE"0402LF"
WATTAGE"1/16W"
PART_NUMBER"CS03322FB03";
"B"
$PN"2"102;
"A"
$PN"1"107;
%"Q_RES"
"1","(-6725,575)","0","pure_quanta","I25";
;
LOCATION"R648"
$SEC"1"
CDS_SEC"1"
VALUE"33"
CDS_LIB"pure_quanta"
BOM_COST"MEM"
WATTAGE"1/16W"
MATERIAL"CHIP"
TOLERANCE"5%"
PACK_TYPE"0402LF"
PART_NUMBER"CS03302JB10";
"B"
$PN"2"6;
"A"
$PN"1"2;
%"Q_RES"
"1","(-2300,2225)","0","pure_quanta","I250";
;
LOCATION"R3476"
$SEC"1"
CDS_SEC"1"
MATERIAL"CHIP"
TOLERANCE"1%"
VALUE"33.2"
CDS_LIB"pure_quanta"
PACK_TYPE"0402LF"
WATTAGE"1/16W"
PART_NUMBER"CS03322FB03";
"B"
$PN"2"274;
"A"
$PN"1"106;
%"Q_RES"
"1","(-2300,2125)","0","pure_quanta","I251";
;
LOCATION"R3481"
$SEC"1"
CDS_SEC"1"
TOLERANCE"1%"
MATERIAL"CHIP"
VALUE"33.2"
WATTAGE"1/16W"
PACK_TYPE"0402LF"
CDS_LIB"pure_quanta"
PART_NUMBER"CS03322FB03";
"B"
$PN"2"273;
"A"
$PN"1"103;
%"Q_RES"
"1","(-2300,2075)","0","pure_quanta","I254";
;
LOCATION"R3484"
$SEC"1"
CDS_SEC"1"
TOLERANCE"1%"
MATERIAL"CHIP"
VALUE"33.2"
WATTAGE"1/16W"
PACK_TYPE"0402LF"
CDS_LIB"pure_quanta"
PART_NUMBER"CS03322FB03";
"B"
$PN"2"98;
"A"
$PN"1"322;
%"Q_RES"
"1","(-2300,2025)","0","pure_quanta","I255";
;
LOCATION"R3485"
$SEC"1"
CDS_SEC"1"
TOLERANCE"1%"
VALUE"33.2"
MATERIAL"CHIP"
WATTAGE"1/16W"
PACK_TYPE"0402LF"
CDS_LIB"pure_quanta"
PART_NUMBER"CS03322FB03";
"B"
$PN"2"95;
"A"
$PN"1"323;
%"Q_RES"
"1","(-2300,1975)","0","pure_quanta","I258";
;
LOCATION"R3486"
$SEC"1"
CDS_SEC"1"
MATERIAL"CHIP"
TOLERANCE"1%"
VALUE"33.2"
WATTAGE"1/16W"
PACK_TYPE"0402LF"
CDS_LIB"pure_quanta"
PART_NUMBER"CS03322FB03";
"B"
$PN"2"97;
"A"
$PN"1"324;
%"Q_RES"
"1","(-2300,1925)","0","pure_quanta","I259";
;
LOCATION"R3505"
$SEC"1"
CDS_SEC"1"
TOLERANCE"1%"
VALUE"33.2"
MATERIAL"CHIP"
CDS_LIB"pure_quanta"
PACK_TYPE"0402LF"
WATTAGE"1/16W"
PART_NUMBER"CS03322FB03";
"B"
$PN"2"283;
"A"
$PN"1"325;
%"Q_RES"
"1","(-2300,1875)","0","pure_quanta","I262";
;
LOCATION"R2846"
$SEC"1"
CDS_SEC"1"
TOLERANCE"1%"
VALUE"33.2"
MATERIAL"CHIP"
CDS_LIB"pure_quanta"
PACK_TYPE"0402LF"
WATTAGE"1/16W"
PART_NUMBER"CS03322FB03";
"B"
$PN"2"307;
"A"
$PN"1"326;
%"Q_RES"
"1","(-2300,1775)","0","pure_quanta","I263";
;
LOCATION"R2844"
$SEC"1"
CDS_SEC"1"
TOLERANCE"1%"
VALUE"33.2"
MATERIAL"CHIP"
WATTAGE"1/16W"
PACK_TYPE"0402LF"
CDS_LIB"pure_quanta"
PART_NUMBER"CS03322FB03";
"B"
$PN"2"285;
"A"
$PN"1"71;
%"Q_RES"
"1","(-2300,1825)","0","pure_quanta","I266";
;
LOCATION"R2847"
$SEC"1"
CDS_SEC"1"
TOLERANCE"1%"
VALUE"33.2"
MATERIAL"CHIP"
WATTAGE"1/16W"
PACK_TYPE"0402LF"
CDS_LIB"pure_quanta"
PART_NUMBER"CS03322FB03";
"B"
$PN"2"284;
"A"
$PN"1"72;
%"Q_RES"
"1","(-2300,1725)","0","pure_quanta","I268";
;
LOCATION"R3066"
$SEC"1"
CDS_SEC"1"
TOLERANCE"1%"
VALUE"33.2"
MATERIAL"CHIP"
CDS_LIB"pure_quanta"
PACK_TYPE"0402LF"
WATTAGE"1/16W"
PART_NUMBER"CS03322FB03";
"B"
$PN"2"306;
"A"
$PN"1"73;
%"Q_RES"
"1","(-2300,1575)","0","pure_quanta","I271";
;
LOCATION"R2663"
$SEC"1"
CDS_SEC"1"
VALUE"33.2"
TOLERANCE"1%"
MATERIAL"CHIP"
CDS_LIB"pure_quanta"
PACK_TYPE"0402LF"
WATTAGE"1/16W"
PART_NUMBER"CS03322FB03";
"B"
$PN"2"303;
"A"
$PN"1"304;
%"Q_RES"
"1","(-2300,1525)","0","pure_quanta","I272";
;
LOCATION"R2664"
$SEC"1"
CDS_SEC"1"
MATERIAL"CHIP"
TOLERANCE"1%"
VALUE"33.2"
CDS_LIB"pure_quanta"
PACK_TYPE"0402LF"
WATTAGE"1/16W"
PART_NUMBER"CS03322FB03";
"B"
$PN"2"286;
"A"
$PN"1"92;
%"Q_RES"
"1","(-2300,1475)","0","pure_quanta","I274";
;
LOCATION"R11667"
$SEC"1"
CDS_SEC"1"
VALUE"33.2"
TOLERANCE"1%"
MATERIAL"CHIP"
WATTAGE"1/16W"
PACK_TYPE"0402LF"
CDS_LIB"pure_quanta"
PART_NUMBER"CS03322FB03";
"B"
$PN"2"56;
"A"
$PN"1"327;
%"Q_RES"
"1","(-2300,1375)","0","pure_quanta","I276";
;
LOCATION"R3324"
$SEC"1"
CDS_SEC"1"
TOLERANCE"1%"
VALUE"33.2"
MATERIAL"CHIP"
WATTAGE"1/16W"
PACK_TYPE"0402LF"
CDS_LIB"pure_quanta"
PART_NUMBER"CS03322FB03";
"B"
$PN"2"50;
"A"
$PN"1"93;
%"Q_RES"
"1","(-2300,1275)","0","pure_quanta","I278";
;
LOCATION"R3482"
$SEC"1"
CDS_SEC"1"
VALUE"33.2"
TOLERANCE"1%"
MATERIAL"CHIP"
WATTAGE"1/16W"
PACK_TYPE"0402LF"
CDS_LIB"pure_quanta"
PART_NUMBER"CS03322FB03";
"B"
$PN"2"52;
"A"
$PN"1"287;
%"Q_RES"
"1","(-6725,1425)","0","pure_quanta","I28";
;
LOCATION"R6048"
$SEC"1"
CDS_SEC"1"
VALUE"0"
PACK_TYPE"0402LF"
TOLERANCE"5%"
MATERIAL"CHIP"
WATTAGE"1/16W"
BOM_COST"MEM"
CDS_LIB"pure_quanta"
PART_NUMBER"CS00002JB13";
"B"
$PN"2"20;
"A"
$PN"1"301;
%"Q_RES"
"1","(-2300,1075)","0","pure_quanta","I281";
;
LOCATION"R3479"
$SEC"1"
CDS_SEC"1"
MATERIAL"CHIP"
TOLERANCE"1%"
VALUE"33.2"
CDS_LIB"pure_quanta"
PACK_TYPE"0402LF"
WATTAGE"1/16W"
PART_NUMBER"CS03322FB03";
"B"
$PN"2"55;
"A"
$PN"1"331;
%"Q_RES"
"1","(-6725,3175)","0","pure_quanta","I284";
;
LOCATION"R2261"
$SEC"1"
CDS_SEC"1"
VALUE"33.2"
MATERIAL"CHIP"
TOLERANCE"1%"
WATTAGE"1/16W"
PACK_TYPE"0402LF"
CDS_LIB"pure_quanta"
PART_NUMBER"CS03322FB03";
"B"
$PN"2"70;
"A"
$PN"1"68;
%"Q_RES"
"1","(-6725,3125)","0","pure_quanta","I286";
;
LOCATION"R3477"
$SEC"1"
CDS_SEC"1"
TOLERANCE"1%"
MATERIAL"CHIP"
VALUE"33.2"
WATTAGE"1/16W"
PACK_TYPE"0402LF"
CDS_LIB"pure_quanta"
PART_NUMBER"CS03322FB03";
"B"
$PN"2"65;
"A"
$PN"1"67;
%"Q_RES"
"1","(-6725,2775)","0","pure_quanta","I288";
;
LOCATION"R3478"
$SEC"1"
CDS_SEC"1"
MATERIAL"CHIP"
VALUE"33.2"
TOLERANCE"1%"
PACK_TYPE"0402LF"
WATTAGE"1/16W"
CDS_LIB"pure_quanta"
PART_NUMBER"CS03322FB03";
"B"
$PN"2"36;
"A"
$PN"1"59;
%"Q_RES"
"1","(-6725,1325)","0","pure_quanta","I29";
;
LOCATION"R1282"
$SEC"1"
CDS_SEC"1"
VALUE"33"
BOM_COST"MEM"
WATTAGE"1/16W"
MATERIAL"CHIP"
TOLERANCE"5%"
PACK_TYPE"0402LF"
CDS_LIB"pure_quanta"
PART_NUMBER"CS03302JB10";
"B"
$PN"2"19;
"A"
$PN"1"302;
%"Q_RES"
"1","(-6725,2575)","0","pure_quanta","I290";
;
LOCATION"R3483"
$SEC"1"
CDS_SEC"1"
VALUE"33.2"
TOLERANCE"1%"
MATERIAL"CHIP"
WATTAGE"1/16W"
PACK_TYPE"0402LF"
CDS_LIB"pure_quanta"
PART_NUMBER"CS03322FB03";
"B"
$PN"2"33;
"A"
$PN"1"335;
%"Q_RES"
"1","(-6725,2525)","0","pure_quanta","I293";
;
LOCATION"R2845"
$SEC"1"
CDS_SEC"1"
VALUE"33.2"
MATERIAL"CHIP"
TOLERANCE"1%"
CDS_LIB"pure_quanta"
PACK_TYPE"0402LF"
WATTAGE"1/16W"
PART_NUMBER"CS03322FB03";
"B"
$PN"2"32;
"A"
$PN"1"336;
%"Q_RES"
"1","(-6725,2275)","0","pure_quanta","I294";
;
LOCATION"R2262"
$SEC"1"
CDS_SEC"1"
VALUE"33.2"
TOLERANCE"1%"
MATERIAL"CHIP"
CDS_LIB"pure_quanta"
PACK_TYPE"0402LF"
WATTAGE"1/16W"
PART_NUMBER"CS03322FB03";
"B"
$PN"2"279;
"A"
$PN"1"62;
%"Q_RES"
"1","(-6725,2225)","0","pure_quanta","I295";
;
LOCATION"R4608"
$SEC"1"
CDS_SEC"1"
MATERIAL"CHIP"
VALUE"33.2"
TOLERANCE"1%"
CDS_LIB"pure_quanta"
PACK_TYPE"0402LF"
WATTAGE"1/16W"
PART_NUMBER"CS03322FB03";
"B"
$PN"2"278;
"A"
$PN"1"205;
%"Q_RES"
"2","(-275,1125)","0","pure_quanta","I298";
;
LOCATION"R6085"
$SEC"1"
CDS_SEC"1"
WATTAGE"1/16W"
MATERIAL"CHIP"
TOLERANCE"1%"
VALUE"10K"
PACK_TYPE"0402LF"
CDS_LIB"pure_quanta"
PART_NUMBER"CS31002FB08";
"A"
$PN"1"1;
"B"
$PN"2"54;
%"UNIVERSAL_POWER"
"1","(-275,1350)","2","pure_quanta_power","I299";
;
HDL_POWER"P3V3_AUX"
CDS_LIB"pure_quanta_power";
"A"1;
%"Q_RES"
"1","(-6725,1525)","0","pure_quanta","I30";
;
LOCATION"R283"
$SEC"1"
CDS_SEC"1"
VALUE"0"
CDS_LIB"pure_quanta"
BOM_COST"MEM"
WATTAGE"1/16W"
MATERIAL"CHIP"
TOLERANCE"5%"
PACK_TYPE"0402LF"
PART_NUMBER"CS00002JB13";
"B"
$PN"2"16;
"A"
$PN"1"299;
%"Q_RES"
"1","(-6725,675)","0","pure_quanta","I301";
;
LOCATION"R4557"
$SEC"1"
CDS_SEC"1"
TOLERANCE"1%"
VALUE"33.2"
MATERIAL"CHIP"
CDS_LIB"pure_quanta"
PACK_TYPE"0402LF"
WATTAGE"1/16W"
PART_NUMBER"CS03322FB03";
"B"
$PN"2"7;
"A"
$PN"1"330;
%"Q_RES"
"1","(-3225,4125)","0","pure_quanta","I303";
;
LOCATION"R195"
$SEC"1"
CDS_SEC"1"
VALUE"33"
CDS_LIB"pure_quanta"
BOM_COST"MEM"
WATTAGE"1/16W"
MATERIAL"CHIP"
TOLERANCE"5%"
PACK_TYPE"0402LF"
PART_NUMBER"CS03302JB10";
"B"
$PN"2"121;
"A"
$PN"1"161;
%"Q_RES"
"1","(-6725,1575)","0","pure_quanta","I31";
;
LOCATION"R282"
$SEC"1"
CDS_SEC"1"
VALUE"33"
CDS_LIB"pure_quanta"
BOM_COST"MEM"
WATTAGE"1/16W"
MATERIAL"CHIP"
TOLERANCE"5%"
PACK_TYPE"0402LF"
PART_NUMBER"CS03302JB10";
"B"
$PN"2"293;
"A"
$PN"1"298;
%"Q_RES"
"1","(-6725,1475)","0","pure_quanta","I311";
;
LOCATION"R2939"
$SEC"1"
CDS_SEC"1"
MATERIAL"CHIP"
TOLERANCE"1%"
VALUE"33.2"
WATTAGE"1/16W"
PACK_TYPE"0402LF"
CDS_LIB"pure_quanta"
PART_NUMBER"CS03322FB03";
"B"
$PN"2"294;
"A"
$PN"1"300;
%"Q_RES"
"1","(-6725,2725)","0","pure_quanta","I315";
;
LOCATION"R8000"
$SEC"1"
CDS_SEC"1"
MATERIAL"CHIP"
TOLERANCE"1%"
VALUE"33.2"
WATTAGE"1/16W"
PACK_TYPE"0402LF"
CDS_LIB"pure_quanta"
PART_NUMBER"CS03322FB03";
"B"
$PN"2"35;
"A"
$PN"1"58;
%"Q_RES"
"1","(-3225,5575)","0","pure_quanta","I318";
;
LOCATION"R8021"
SEC"1"
VALUE"0"
PACK_TYPE"0402LF"
SEC_TYPE"0402LF"
TOLERANCE"5%"
MATERIAL"CHIP"
WATTAGE"1/16W"
BOM_COST"MEM"
CDS_LIB"pure_quanta"
PART_NUMBER"CS00002JB13";
"B"
$PN"2"176;
"A"
$PN"1"222;
%"Q_RES"
"1","(-3225,5875)","0","pure_quanta","I319";
;
LOCATION"R8032"
$SEC"1"
CDS_SEC"1"
VALUE"0"
CDS_LIB"pure_quanta"
PACK_TYPE"0402LF"
TOLERANCE"5%"
MATERIAL"CHIP"
WATTAGE"1/16W"
BOM_COST"MEM"
PART_NUMBER"CS00002JB13";
"B"
$PN"2"133;
"A"
$PN"1"215;
%"Q_RES"
"1","(-6725,1625)","0","pure_quanta","I32";
;
LOCATION"R218"
$SEC"1"
CDS_SEC"1"
VALUE"33"
CDS_LIB"pure_quanta"
BOM_COST"MEM"
WATTAGE"1/16W"
MATERIAL"CHIP"
TOLERANCE"5%"
PACK_TYPE"0402LF"
PART_NUMBER"CS03302JB10";
"B"
$PN"2"21;
"A"
$PN"1"297;
%"Q_RES"
"1","(-6425,5775)","0","pure_quanta","I322";
;
LOCATION"R6710"
$SEC"1"
CDS_SEC"1"
VALUE"0"
CDS_LIB"pure_quanta"
PACK_TYPE"0402LF"
TOLERANCE"5%"
MATERIAL"CHIP"
WATTAGE"1/16W"
BOM_COST"MEM"
PART_NUMBER"CS00002JB13";
"B"
$PN"2"262;
"A"
$PN"1"253;
%"Q_RES"
"1","(-6425,5725)","0","pure_quanta","I324";
;
LOCATION"R6711"
$SEC"1"
CDS_SEC"1"
VALUE"0"
CDS_LIB"pure_quanta"
PACK_TYPE"0402LF"
TOLERANCE"5%"
MATERIAL"CHIP"
WATTAGE"1/16W"
BOM_COST"MEM"
PART_NUMBER"CS00002JB13";
"B"
$PN"2"263;
"A"
$PN"1"252;
%"Q_RES"
"1","(-6425,5275)","0","pure_quanta","I326";
;
LOCATION"R6740"
$SEC"1"
CDS_SEC"1"
VALUE"0"
CDS_LIB"pure_quanta"
PACK_TYPE"0402LF"
TOLERANCE"5%"
MATERIAL"CHIP"
WATTAGE"1/16W"
BOM_COST"MEM"
PART_NUMBER"CS00002JB13";
"B"
$PN"2"184;
"A"
$PN"1"250;
%"Q_RES"
"1","(-6425,5225)","0","pure_quanta","I327";
;
LOCATION"R6741"
$SEC"1"
CDS_SEC"1"
VALUE"0"
PACK_TYPE"0402LF"
TOLERANCE"5%"
MATERIAL"CHIP"
WATTAGE"1/16W"
BOM_COST"MEM"
CDS_LIB"pure_quanta"
PART_NUMBER"CS00002JB13";
"B"
$PN"2"183;
"A"
$PN"1"111;
%"Q_RES"
"1","(-6725,1775)","0","pure_quanta","I33";
;
LOCATION"R176"
$SEC"1"
CDS_SEC"1"
VALUE"33"
BOM_COST"MEM"
CDS_LIB"pure_quanta"
WATTAGE"1/16W"
MATERIAL"CHIP"
TOLERANCE"5%"
PACK_TYPE"0402LF"
PART_NUMBER"CS03302JB10";
"B"
$PN"2"23;
"A"
$PN"1"289;
%"Q_RES"
"1","(-3225,3775)","0","pure_quanta","I330";
;
LOCATION"R6777"
$SEC"1"
CDS_SEC"1"
VALUE"0"
PACK_TYPE"0402LF"
TOLERANCE"5%"
MATERIAL"CHIP"
WATTAGE"1/16W"
BOM_COST"MEM"
CDS_LIB"pure_quanta"
PART_NUMBER"CS00002JB13";
"B"
$PN"2"78;
"A"
$PN"1"207;
%"Q_RES"
"1","(-3225,3925)","0","pure_quanta","I332";
;
LOCATION"R6781"
$SEC"1"
CDS_SEC"1"
VALUE"0"
CDS_LIB"pure_quanta"
BOM_COST"MEM"
WATTAGE"1/16W"
MATERIAL"CHIP"
TOLERANCE"5%"
PACK_TYPE"0402LF"
PART_NUMBER"CS00002JB13";
"B"
$PN"2"173;
"A"
$PN"1"208;
%"Q_RES"
"1","(-6425,4425)","0","pure_quanta","I334";
;
LOCATION"R6792"
$SEC"1"
CDS_SEC"1"
VALUE"0"
BOM_COST"MEM"
WATTAGE"1/16W"
MATERIAL"CHIP"
TOLERANCE"5%"
PACK_TYPE"0402LF"
CDS_LIB"pure_quanta"
PART_NUMBER"CS00002JB13";
"B"
$PN"2"122;
"A"
$PN"1"89;
%"Q_RES"
"1","(-6425,4375)","0","pure_quanta","I335";
;
LOCATION"R6793"
$SEC"1"
CDS_SEC"1"
VALUE"0"
PACK_TYPE"0402LF"
TOLERANCE"5%"
MATERIAL"CHIP"
WATTAGE"1/16W"
BOM_COST"MEM"
CDS_LIB"pure_quanta"
PART_NUMBER"CS00002JB13";
"B"
$PN"2"123;
"A"
$PN"1"90;
%"Q_RES"
"1","(-6425,4075)","0","pure_quanta","I338";
;
LOCATION"R6798"
$SEC"1"
CDS_SEC"1"
VALUE"0"
CDS_LIB"pure_quanta"
BOM_COST"MEM"
WATTAGE"1/16W"
MATERIAL"CHIP"
TOLERANCE"5%"
PACK_TYPE"0402LF"
PART_NUMBER"CS00002JB13";
"B"
$PN"2"147;
"A"
$PN"1"118;
%"Q_RES"
"1","(-6425,4025)","0","pure_quanta","I339";
;
LOCATION"R6799"
$SEC"1"
CDS_SEC"1"
VALUE"0"
PACK_TYPE"0402LF"
TOLERANCE"5%"
MATERIAL"CHIP"
WATTAGE"1/16W"
BOM_COST"MEM"
CDS_LIB"pure_quanta"
PART_NUMBER"CS00002JB13";
"B"
$PN"2"128;
"A"
$PN"1"117;
%"Q_RES"
"1","(-6725,1825)","0","pure_quanta","I34";
;
LOCATION"R6047"
$SEC"1"
CDS_SEC"1"
VALUE"0"
PACK_TYPE"0402LF"
TOLERANCE"5%"
MATERIAL"CHIP"
WATTAGE"1/16W"
BOM_COST"MEM"
CDS_LIB"pure_quanta"
PART_NUMBER"CS00002JB13";
"B"
$PN"2"24;
"A"
$PN"1"290;
%"Q_RES"
"1","(-6425,3975)","0","pure_quanta","I342";
;
LOCATION"R6804"
$SEC"1"
CDS_SEC"1"
VALUE"0"
CDS_LIB"pure_quanta"
PACK_TYPE"0402LF"
TOLERANCE"5%"
MATERIAL"CHIP"
WATTAGE"1/16W"
BOM_COST"MEM"
PART_NUMBER"CS00002JB13";
"B"
$PN"2"132;
"A"
$PN"1"115;
%"Q_RES"
"1","(-6425,3925)","0","pure_quanta","I343";
;
LOCATION"R6805"
$SEC"1"
CDS_SEC"1"
VALUE"0"
BOM_COST"MEM"
WATTAGE"1/16W"
MATERIAL"CHIP"
TOLERANCE"5%"
PACK_TYPE"0402LF"
CDS_LIB"pure_quanta"
PART_NUMBER"CS00002JB13";
"B"
$PN"2"146;
"A"
$PN"1"116;
%"Q_RES"
"1","(-6425,3875)","0","pure_quanta","I344";
;
LOCATION"R6806"
$SEC"1"
CDS_SEC"1"
VALUE"0"
CDS_LIB"pure_quanta"
BOM_COST"MEM"
WATTAGE"1/16W"
MATERIAL"CHIP"
TOLERANCE"5%"
PACK_TYPE"0402LF"
PART_NUMBER"CS00002JB13";
"B"
$PN"2"145;
"A"
$PN"1"66;
%"Q_RES"
"1","(-6425,3825)","0","pure_quanta","I345";
;
LOCATION"R6807"
$SEC"1"
CDS_SEC"1"
VALUE"0"
CDS_LIB"pure_quanta"
PACK_TYPE"0402LF"
TOLERANCE"5%"
MATERIAL"CHIP"
WATTAGE"1/16W"
BOM_COST"MEM"
PART_NUMBER"CS00002JB13";
"B"
$PN"2"131;
"A"
$PN"1"129;
%"Q_RES"
"1","(-6725,2025)","0","pure_quanta","I35";
;
LOCATION"R5099"
$SEC"1"
CDS_SEC"1"
VALUE"0"
CDS_LIB"pure_quanta"
BOM_COST"MEM"
WATTAGE"1/16W"
MATERIAL"CHIP"
TOLERANCE"5%"
PACK_TYPE"0402LF"
PART_NUMBER"CS00002JB13";
"B"
$PN"2"26;
"A"
$PN"1"239;
%"Q_RES"
"1","(-3225,5825)","0","pure_quanta","I350";
;
LOCATION"R6823"
$SEC"1"
CDS_SEC"1"
VALUE"0"
CDS_LIB"pure_quanta"
BOM_COST"MEM"
WATTAGE"1/16W"
MATERIAL"CHIP"
TOLERANCE"5%"
PACK_TYPE"0402LF"
PART_NUMBER"CS00002JB13";
"B"
$PN"2"220;
"A"
$PN"1"221;
%"Q_RES"
"1","(-3225,4875)","0","pure_quanta","I351";
;
LOCATION"R6824"
$SEC"1"
CDS_SEC"1"
VALUE"0"
CDS_LIB"pure_quanta"
PACK_TYPE"0402LF"
TOLERANCE"5%"
MATERIAL"CHIP"
WATTAGE"1/16W"
BOM_COST"MEM"
PART_NUMBER"CS00002JB13";
"B"
$PN"2"172;
"A"
$PN"1"236;
%"Q_RES"
"1","(-3225,4525)","0","pure_quanta","I352";
;
LOCATION"R6825"
$SEC"1"
CDS_SEC"1"
VALUE"0"
PACK_TYPE"0402LF"
TOLERANCE"5%"
MATERIAL"CHIP"
WATTAGE"1/16W"
BOM_COST"MEM"
CDS_LIB"pure_quanta"
PART_NUMBER"CS00002JB13";
"B"
$PN"2"171;
"A"
$PN"1"210;
%"Q_RES"
"1","(-3225,4425)","0","pure_quanta","I353";
;
LOCATION"R6826"
$SEC"1"
CDS_SEC"1"
VALUE"0"
PACK_TYPE"0402LF"
TOLERANCE"5%"
MATERIAL"CHIP"
WATTAGE"1/16W"
BOM_COST"MEM"
CDS_LIB"pure_quanta"
PART_NUMBER"CS00002JB13";
"B"
$PN"2"169;
"A"
$PN"1"199;
%"Q_RES"
"1","(-6725,1875)","0","pure_quanta","I36";
;
LOCATION"R224"
$SEC"1"
CDS_SEC"1"
VALUE"33"
BOM_COST"MEM"
CDS_LIB"pure_quanta"
WATTAGE"1/16W"
MATERIAL"CHIP"
TOLERANCE"5%"
PACK_TYPE"0402LF"
PART_NUMBER"CS03302JB10";
"B"
$PN"2"296;
"A"
$PN"1"288;
%"Q_RES"
"1","(-6425,5875)","0","pure_quanta","I360";
;
LOCATION"R6852"
$SEC"1"
CDS_SEC"1"
VALUE"0"
CDS_LIB"pure_quanta"
PACK_TYPE"0402LF"
TOLERANCE"5%"
MATERIAL"CHIP"
WATTAGE"1/16W"
BOM_COST"MEM"
PART_NUMBER"CS00002JB13";
"B"
$PN"2"267;
"A"
$PN"1"255;
%"Q_RES"
"1","(-6425,5625)","0","pure_quanta","I362";
;
LOCATION"R6853"
$SEC"1"
CDS_SEC"1"
VALUE"0"
PACK_TYPE"0402LF"
TOLERANCE"5%"
MATERIAL"CHIP"
WATTAGE"1/16W"
BOM_COST"MEM"
CDS_LIB"pure_quanta"
PART_NUMBER"CS00002JB13";
"B"
$PN"2"271;
"A"
$PN"1"264;
%"Q_RES"
"1","(-6725,1125)","0","pure_quanta","I364";
;
LOCATION"R6854"
$SEC"1"
CDS_SEC"1"
VALUE"33"
BOM_COST"MEM"
WATTAGE"1/16W"
MATERIAL"CHIP"
TOLERANCE"5%"
PACK_TYPE"0402LF"
CDS_LIB"pure_quanta"
PART_NUMBER"CS03302JB10";
"B"
$PN"2"13;
"A"
$PN"1"328;
%"Q_RES"
"1","(-2275,925)","0","pure_quanta","I366";
;
LOCATION"R6855"
$SEC"1"
CDS_SEC"1"
VALUE"33"
CDS_LIB"pure_quanta"
BOM_COST"MEM"
WATTAGE"1/16W"
MATERIAL"CHIP"
TOLERANCE"5%"
PACK_TYPE"0402LF"
PART_NUMBER"CS03302JB10";
"B"
$PN"2"53;
"A"
$PN"1"45;
%"Q_RES"
"1","(-6725,2075)","0","pure_quanta","I57";
;
LOCATION"R289"
$SEC"1"
CDS_SEC"1"
VALUE"33"
PACK_TYPE"0402LF"
TOLERANCE"5%"
MATERIAL"CHIP"
WATTAGE"1/16W"
BOM_COST"MEM"
CDS_LIB"pure_quanta"
PART_NUMBER"CS03302JB10";
"B"
$PN"2"292;
"A"
$PN"1"238;
%"Q_RES"
"1","(-6725,2175)","0","pure_quanta","I58";
;
LOCATION"R279"
$SEC"1"
CDS_SEC"1"
VALUE"33"
PACK_TYPE"0402LF"
TOLERANCE"5%"
MATERIAL"CHIP"
WATTAGE"1/16W"
BOM_COST"MEM"
CDS_LIB"pure_quanta"
PART_NUMBER"CS03302JB10";
"B"
$PN"2"28;
"A"
$PN"1"206;
%"Q_RES"
"1","(-6725,2125)","0","pure_quanta","I59";
;
LOCATION"R280"
$SEC"1"
CDS_SEC"1"
VALUE"0"
CDS_LIB"pure_quanta"
PACK_TYPE"0402LF"
TOLERANCE"5%"
MATERIAL"CHIP"
WATTAGE"1/16W"
BOM_COST"MEM"
PART_NUMBER"CS00002JB13";
"B"
$PN"2"27;
"A"
$PN"1"237;
%"Q_RES"
"1","(-6725,2425)","0","pure_quanta","I60";
;
LOCATION"R6055"
$SEC"1"
CDS_SEC"1"
VALUE"0"
PACK_TYPE"0402LF"
TOLERANCE"5%"
MATERIAL"CHIP"
WATTAGE"1/16W"
CDS_LIB"pure_quanta"
BOM_COST"MEM"
PART_NUMBER"CS00002JB13";
"B"
$PN"2"31;
"A"
$PN"1"337;
%"Q_RES"
"1","(-6725,2475)","0","pure_quanta","I61";
;
LOCATION"R209"
$SEC"1"
CDS_SEC"1"
VALUE"0"
BOM_COST"MEM"
CDS_LIB"pure_quanta"
WATTAGE"1/16W"
MATERIAL"CHIP"
TOLERANCE"5%"
PACK_TYPE"0402LF"
PART_NUMBER"CS00002JB13";
"B"
$PN"2"280;
"A"
$PN"1"63;
%"Q_RES"
"1","(-6725,2625)","0","pure_quanta","I62";
;
LOCATION"R286"
$SEC"1"
CDS_SEC"1"
VALUE"0"
PACK_TYPE"0402LF"
TOLERANCE"5%"
MATERIAL"CHIP"
WATTAGE"1/16W"
CDS_LIB"pure_quanta"
BOM_COST"MEM"
PART_NUMBER"CS00002JB13";
"B"
$PN"2"281;
"A"
$PN"1"57;
%"Q_RES"
"1","(-6725,2675)","0","pure_quanta","I63";
;
LOCATION"R1563"
$SEC"1"
CDS_SEC"1"
VALUE"33"
CDS_LIB"pure_quanta"
PACK_TYPE"0402LF"
TOLERANCE"5%"
MATERIAL"CHIP"
WATTAGE"1/16W"
BOM_COST"MEM"
PART_NUMBER"CS03302JB10";
"B"
$PN"2"34;
"A"
$PN"1"64;
%"Q_RES"
"1","(-6725,2975)","0","pure_quanta","I64";
;
LOCATION"R6046"
$SEC"1"
CDS_SEC"1"
VALUE"100"
BOM_COST"MEM"
CDS_LIB"pure_quanta"
WATTAGE"1/16W"
MATERIAL"CHIP"
PACK_TYPE"0402LF"
TOLERANCE"1%"
PART_NUMBER"CS11002FB07";
"B"
$PN"2"39;
"A"
$PN"1"60;
%"Q_RES"
"1","(-6725,2825)","0","pure_quanta","I65";
;
LOCATION"R208"
$SEC"1"
CDS_SEC"1"
VALUE"33"
PACK_TYPE"0402LF"
TOLERANCE"5%"
MATERIAL"CHIP"
WATTAGE"1/16W"
BOM_COST"MEM"
CDS_LIB"pure_quanta"
PART_NUMBER"CS03302JB10";
"B"
$PN"2"37;
"A"
$PN"1"334;
%"Q_RES"
"1","(-6725,2875)","0","pure_quanta","I66";
;
LOCATION"R228"
$SEC"1"
CDS_SEC"1"
VALUE"0"
PACK_TYPE"0402LF"
TOLERANCE"5%"
MATERIAL"CHIP"
WATTAGE"1/16W"
CDS_LIB"pure_quanta"
BOM_COST"MEM"
PART_NUMBER"CS00002JB13";
"B"
$PN"2"282;
"A"
$PN"1"333;
%"Q_RES"
"1","(-6725,3025)","0","pure_quanta","I67";
;
LOCATION"R230"
$SEC"1"
CDS_SEC"1"
VALUE"0"
CDS_LIB"pure_quanta"
BOM_COST"MEM"
WATTAGE"1/16W"
MATERIAL"CHIP"
TOLERANCE"5%"
PACK_TYPE"0402LF"
PART_NUMBER"CS00002JB13";
"B"
$PN"2"40;
"A"
$PN"1"61;
%"Q_RES"
"1","(-6725,3075)","0","pure_quanta","I68";
;
LOCATION"R229"
$SEC"1"
CDS_SEC"1"
VALUE"33"
BOM_COST"MEM"
CDS_LIB"pure_quanta"
WATTAGE"1/16W"
MATERIAL"CHIP"
TOLERANCE"5%"
PACK_TYPE"0402LF"
PART_NUMBER"CS03302JB10";
"B"
$PN"2"41;
"A"
$PN"1"332;
END.
